FILE_TYPE = MACRO_DRAWING;
SET COLOR_WIRE YELLOW;
SET COLOR_PROP MONO;
SET COLOR_DOT WHITE;
SET COLOR_ARC YELLOW;
SET COLOR_BODY GREEN;
SET COLOR_NOTE MONO;
SET PROP_DISPLAY VALUE;
SET PAGE_NUMBER P120;
FORCEADD OFFPAGE..1
(-7425 3950);
FORCEPROP 2 LAST $XR3 247 
J 0
(-7676 3914);
DISPLAY 0.638298 (-7676 3914);
PAINT MONO (-7676 3914);
FORCEPROP 2 LAST $XR2 190 
J 0
(-7916 3950);
DISPLAY 0.638298 (-7916 3950);
PAINT MONO (-7916 3950);
FORCEPROP 2 LAST $XR1 147 
J 0
(-7796 3950);
DISPLAY 0.638298 (-7796 3950);
PAINT MONO (-7796 3950);
FORCEPROP 2 LAST $XR0 92 
J 0
(-7676 3950);
DISPLAY 0.638298 (-7676 3950);
PAINT MONO (-7676 3950);
FORCEPROP 2 LAST PATH I111
J 0
(-7375 4025);
DISPLAY 1.021277 (-7375 4025);
PAINT ORANGE (-7375 4025);
DISPLAY INVISIBLE (-7375 4025);
FORCEPROP 1 LAST COMMENT_BODY TRUE
J 0
(-7300 3850);
DISPLAY 1.404255 (-7300 3850);
PAINT PEACH (-7300 3850);
DISPLAY INVISIBLE (-7300 3850);
FORCEPROP 1 LAST OFFPAGE TRUE
J 0
(-7100 3825);
PAINT GREEN (-7100 3825);
DISPLAY INVISIBLE (-7100 3825);
FORCEPROP 2 LAST CDS_LIB mstr_standard
J 0
(-7425 3950);
PAINT ORANGE (-7425 3950);
DISPLAY INVISIBLE (-7425 3950);
FORCEADD OFFPAGE..5
(-7425 4000);
FORCEPROP 2 LAST $XR1 156 
J 0
(-7800 4000);
DISPLAY 0.638298 (-7800 4000);
PAINT MONO (-7800 4000);
FORCEPROP 2 LAST $XR0 145 
J 0
(-7680 4000);
DISPLAY 0.638298 (-7680 4000);
PAINT MONO (-7680 4000);
FORCEPROP 2 LAST PATH I113
J 0
(-7375 4075);
DISPLAY 1.021277 (-7375 4075);
PAINT ORANGE (-7375 4075);
DISPLAY INVISIBLE (-7375 4075);
FORCEPROP 1 LAST COMMENT_BODY TRUE
J 0
(-7325 3925);
DISPLAY 0.872340 (-7325 3925);
PAINT GREEN (-7325 3925);
DISPLAY INVISIBLE (-7325 3925);
FORCEPROP 1 LAST OFFPAGE TRUE
J 0
(-7100 3875);
DISPLAY 0.872340 (-7100 3875);
PAINT GREEN (-7100 3875);
DISPLAY INVISIBLE (-7100 3875);
FORCEPROP 2 LAST CDS_LIB mstr_standard
J 0
(-7425 4000);
PAINT ORANGE (-7425 4000);
DISPLAY INVISIBLE (-7425 4000);
FORCEADD OFFPAGE..1
R 2
(-1100 4200);
FORCEPROP 2 LAST $XR2 145 
J 0
(-674 4200);
DISPLAY 0.638298 (-674 4200);
PAINT MONO (-674 4200);
FORCEPROP 2 LAST $XR1 133 
J 0
(-794 4200);
DISPLAY 0.638298 (-794 4200);
PAINT MONO (-794 4200);
FORCEPROP 2 LAST $XR0 120 
J 0
(-914 4200);
DISPLAY 0.638298 (-914 4200);
PAINT MONO (-914 4200);
FORCEPROP 2 LAST CDS_LIB mstr_standard
J 0
(-1100 4200);
PAINT ORANGE (-1100 4200);
DISPLAY INVISIBLE (-1100 4200);
FORCEPROP 1 LAST OFFPAGE TRUE
J 2
(-1425 4075);
DISPLAY 0.872340 (-1425 4075);
PAINT GREEN (-1425 4075);
DISPLAY INVISIBLE (-1425 4075);
FORCEPROP 1 LAST COMMENT_BODY TRUE
J 2
(-1225 4100);
DISPLAY 0.872340 (-1225 4100);
PAINT GREEN (-1225 4100);
DISPLAY INVISIBLE (-1225 4100);
FORCEPROP 2 LAST PATH I115
J 0
(-925 4275);
DISPLAY 1.021277 (-925 4275);
PAINT ORANGE (-925 4275);
DISPLAY INVISIBLE (-925 4275);
FORCEADD OFFPAGE..1
R 2
(-1100 4150);
FORCEPROP 2 LAST $XR1 146 
J 0
(-794 4150);
DISPLAY 0.638298 (-794 4150);
PAINT MONO (-794 4150);
FORCEPROP 2 LAST $XR0 157 
J 0
(-914 4150);
DISPLAY 0.638298 (-914 4150);
PAINT MONO (-914 4150);
FORCEPROP 2 LAST CDS_LIB mstr_standard
J 0
(-1100 4150);
PAINT ORANGE (-1100 4150);
DISPLAY INVISIBLE (-1100 4150);
FORCEPROP 1 LAST OFFPAGE TRUE
J 2
(-1425 4025);
DISPLAY 0.872340 (-1425 4025);
PAINT GREEN (-1425 4025);
DISPLAY INVISIBLE (-1425 4025);
FORCEPROP 1 LAST COMMENT_BODY TRUE
J 2
(-1225 4050);
DISPLAY 0.872340 (-1225 4050);
PAINT GREEN (-1225 4050);
DISPLAY INVISIBLE (-1225 4050);
FORCEPROP 2 LAST PATH I116
J 0
(-925 4225);
DISPLAY 1.021277 (-925 4225);
PAINT ORANGE (-925 4225);
DISPLAY INVISIBLE (-925 4225);
FORCEADD OFFPAGE..1
R 2
(-1325 2950);
FORCEPROP 2 LAST $XR0 118 
J 0
(-1139 2950);
DISPLAY 0.638298 (-1139 2950);
PAINT MONO (-1139 2950);
FORCEPROP 2 LAST CDS_LIB mstr_standard
J 0
(-1325 2950);
PAINT ORANGE (-1325 2950);
DISPLAY INVISIBLE (-1325 2950);
FORCEPROP 1 LAST OFFPAGE TRUE
J 2
(-1650 2825);
DISPLAY 0.872340 (-1650 2825);
PAINT GREEN (-1650 2825);
DISPLAY INVISIBLE (-1650 2825);
FORCEPROP 1 LAST COMMENT_BODY TRUE
J 2
(-1450 2850);
DISPLAY 0.872340 (-1450 2850);
PAINT GREEN (-1450 2850);
DISPLAY INVISIBLE (-1450 2850);
FORCEPROP 2 LAST PATH I117
J 0
(-1150 3025);
DISPLAY 1.021277 (-1150 3025);
PAINT ORANGE (-1150 3025);
DISPLAY INVISIBLE (-1150 3025);
FORCEADD OFFPAGE..1
R 2
(-1325 2900);
FORCEPROP 2 LAST $XR0 133 
J 0
(-1139 2900);
DISPLAY 0.638298 (-1139 2900);
PAINT MONO (-1139 2900);
FORCEPROP 2 LAST CDS_LIB mstr_standard
J 0
(-1325 2900);
PAINT ORANGE (-1325 2900);
DISPLAY INVISIBLE (-1325 2900);
FORCEPROP 1 LAST OFFPAGE TRUE
J 2
(-1650 2775);
PAINT GREEN (-1650 2775);
DISPLAY INVISIBLE (-1650 2775);
FORCEPROP 1 LAST COMMENT_BODY TRUE
J 2
(-1450 2800);
DISPLAY 1.404255 (-1450 2800);
PAINT PEACH (-1450 2800);
DISPLAY INVISIBLE (-1450 2800);
FORCEPROP 2 LAST PATH I118
J 0
(-1150 2975);
DISPLAY 1.021277 (-1150 2975);
PAINT ORANGE (-1150 2975);
DISPLAY INVISIBLE (-1150 2975);
FORCEADD OFFPAGE..1
(-7425 3800);
FORCEPROP 2 LAST $XR1 146 
J 0
(-7797 3800);
DISPLAY 0.638298 (-7797 3800);
PAINT MONO (-7797 3800);
FORCEPROP 2 LAST $XR0 168 
J 0
(-7677 3800);
DISPLAY 0.638298 (-7677 3800);
PAINT MONO (-7677 3800);
FORCEPROP 2 LAST PATH I119
J 0
(-7375 3875);
DISPLAY 1.021277 (-7375 3875);
PAINT ORANGE (-7375 3875);
DISPLAY INVISIBLE (-7375 3875);
FORCEPROP 1 LAST COMMENT_BODY TRUE
J 0
(-7300 3700);
DISPLAY 1.404255 (-7300 3700);
PAINT PEACH (-7300 3700);
DISPLAY INVISIBLE (-7300 3700);
FORCEPROP 1 LAST OFFPAGE TRUE
J 0
(-7100 3675);
PAINT GREEN (-7100 3675);
DISPLAY INVISIBLE (-7100 3675);
FORCEPROP 2 LAST CDS_LIB mstr_standard
J 0
(-7425 3800);
PAINT ORANGE (-7425 3800);
DISPLAY INVISIBLE (-7425 3800);
FORCEADD OFFPAGE..1
R 2
(-1100 3900);
FORCEPROP 2 LAST $XR0 125 
J 0
(-914 3900);
DISPLAY 0.638298 (-914 3900);
PAINT MONO (-914 3900);
FORCEPROP 2 LAST CDS_LIB mstr_standard
J 0
(-1100 3900);
PAINT ORANGE (-1100 3900);
DISPLAY INVISIBLE (-1100 3900);
FORCEPROP 1 LAST OFFPAGE TRUE
J 2
(-1425 3775);
PAINT GREEN (-1425 3775);
DISPLAY INVISIBLE (-1425 3775);
FORCEPROP 1 LAST COMMENT_BODY TRUE
J 2
(-1225 3800);
DISPLAY 1.404255 (-1225 3800);
PAINT PEACH (-1225 3800);
DISPLAY INVISIBLE (-1225 3800);
FORCEPROP 2 LAST PATH I140
J 0
(-925 3975);
DISPLAY 1.021277 (-925 3975);
PAINT ORANGE (-925 3975);
DISPLAY INVISIBLE (-925 3975);
FORCEADD OFFPAGE..1
R 2
(-1100 4300);
FORCEPROP 2 LAST $XR0 185 
J 0
(-914 4300);
DISPLAY 0.638298 (-914 4300);
PAINT MONO (-914 4300);
FORCEPROP 2 LAST CDS_LIB mstr_standard
J 0
(-1100 4300);
PAINT ORANGE (-1100 4300);
DISPLAY INVISIBLE (-1100 4300);
FORCEPROP 1 LAST OFFPAGE TRUE
J 2
(-1425 4175);
PAINT GREEN (-1425 4175);
DISPLAY INVISIBLE (-1425 4175);
FORCEPROP 1 LAST COMMENT_BODY TRUE
J 2
(-1225 4200);
DISPLAY 1.404255 (-1225 4200);
PAINT PEACH (-1225 4200);
DISPLAY INVISIBLE (-1225 4200);
FORCEPROP 2 LAST PATH I141
J 0
(-925 4375);
DISPLAY 1.021277 (-925 4375);
PAINT ORANGE (-925 4375);
DISPLAY INVISIBLE (-925 4375);
FORCEADD OFFPAGE..2
(-1450 2650);
FORCEPROP 2 LAST $XR0 189 
J 0
(-1261 2650);
DISPLAY 0.638298 (-1261 2650);
PAINT MONO (-1261 2650);
FORCEPROP 2 LAST CDS_LIB mstr_standard
J 0
(-1450 2650);
PAINT ORANGE (-1450 2650);
DISPLAY INVISIBLE (-1450 2650);
FORCEPROP 1 LAST OFFPAGE TRUE
J 0
(-1125 2525);
DISPLAY 0.872340 (-1125 2525);
PAINT GREEN (-1125 2525);
DISPLAY INVISIBLE (-1125 2525);
FORCEPROP 1 LAST COMMENT_BODY TRUE
J 0
(-1495 2555);
DISPLAY 0.872340 (-1495 2555);
PAINT GREEN (-1495 2555);
DISPLAY INVISIBLE (-1495 2555);
FORCEPROP 2 LAST PATH I142
J 0
(-1275 2725);
DISPLAY 1.021277 (-1275 2725);
PAINT ORANGE (-1275 2725);
DISPLAY INVISIBLE (-1275 2725);
FORCEADD OFFPAGE..2
(-1450 2600);
FORCEPROP 2 LAST $XR0 189 
J 0
(-1261 2600);
DISPLAY 0.638298 (-1261 2600);
PAINT MONO (-1261 2600);
FORCEPROP 2 LAST PATH I143
J 0
(-1275 2675);
DISPLAY 1.021277 (-1275 2675);
PAINT ORANGE (-1275 2675);
DISPLAY INVISIBLE (-1275 2675);
FORCEPROP 1 LAST COMMENT_BODY TRUE
J 0
(-1495 2505);
DISPLAY 0.872340 (-1495 2505);
PAINT GREEN (-1495 2505);
DISPLAY INVISIBLE (-1495 2505);
FORCEPROP 1 LAST OFFPAGE TRUE
J 0
(-1125 2475);
DISPLAY 0.872340 (-1125 2475);
PAINT GREEN (-1125 2475);
DISPLAY INVISIBLE (-1125 2475);
FORCEPROP 2 LAST CDS_LIB mstr_standard
J 0
(-1450 2600);
PAINT ORANGE (-1450 2600);
DISPLAY INVISIBLE (-1450 2600);
FORCEADD OFFPAGE..4
(-1450 2500);
FORCEPROP 2 LAST $XR0 189 
J 0
(-1264 2500);
DISPLAY 0.638298 (-1264 2500);
PAINT MONO (-1264 2500);
FORCEPROP 2 LAST PATH I145
J 0
(-1275 2575);
DISPLAY 1.021277 (-1275 2575);
PAINT ORANGE (-1275 2575);
DISPLAY INVISIBLE (-1275 2575);
FORCEPROP 1 LAST COMMENT_BODY TRUE
J 0
(-1475 2400);
DISPLAY 0.872340 (-1475 2400);
PAINT GREEN (-1475 2400);
DISPLAY INVISIBLE (-1475 2400);
FORCEPROP 1 LAST OFFPAGE TRUE
J 0
(-1125 2375);
DISPLAY 0.872340 (-1125 2375);
PAINT GREEN (-1125 2375);
DISPLAY INVISIBLE (-1125 2375);
FORCEPROP 2 LAST CDS_LIB mstr_standard
J 0
(-1450 2500);
PAINT ORANGE (-1450 2500);
DISPLAY INVISIBLE (-1450 2500);
FORCEADD OFFPAGE..2
(-1450 2550);
FORCEPROP 2 LAST $XR0 189 
J 0
(-1261 2550);
DISPLAY 0.638298 (-1261 2550);
PAINT MONO (-1261 2550);
FORCEPROP 2 LAST PATH I146
J 0
(-1275 2625);
DISPLAY 1.021277 (-1275 2625);
PAINT ORANGE (-1275 2625);
DISPLAY INVISIBLE (-1275 2625);
FORCEPROP 1 LAST COMMENT_BODY TRUE
J 0
(-1495 2455);
DISPLAY 0.872340 (-1495 2455);
PAINT GREEN (-1495 2455);
DISPLAY INVISIBLE (-1495 2455);
FORCEPROP 1 LAST OFFPAGE TRUE
J 0
(-1125 2425);
DISPLAY 0.872340 (-1125 2425);
PAINT GREEN (-1125 2425);
DISPLAY INVISIBLE (-1125 2425);
FORCEPROP 2 LAST CDS_LIB mstr_standard
J 0
(-1450 2550);
PAINT ORANGE (-1450 2550);
DISPLAY INVISIBLE (-1450 2550);
FORCEADD LBG_CORE_QAT_EXT_D..7
(-3750 2800);
FORCEPROP 2 LASTPIN (-5350 4150) $PN BL48
J 2
(-5360 4160);
DISPLAY 0.617021 (-5360 4160);
PAINT ORANGE (-5360 4160);
FORCEPROP 2 LASTPIN (-5350 3750) $PN AY52
J 2
(-5360 3760);
DISPLAY 0.617021 (-5360 3760);
PAINT ORANGE (-5360 3760);
FORCEPROP 2 LASTPIN (-5350 1800) $PN BD13
J 2
(-5360 1810);
DISPLAY 0.617021 (-5360 1810);
PAINT ORANGE (-5360 1810);
FORCEPROP 2 LASTPIN (-2150 1400) $PN BK2
J 0
(-2140 1410);
DISPLAY 0.617021 (-2140 1410);
PAINT ORANGE (-2140 1410);
FORCEPROP 2 LASTPIN (-5350 2600) $PN AK13
J 2
(-5360 2610);
DISPLAY 0.617021 (-5360 2610);
PAINT ORANGE (-5360 2610);
FORCEPROP 2 LASTPIN (-5350 3950) $PN AT52
J 2
(-5360 3960);
DISPLAY 0.617021 (-5360 3960);
PAINT ORANGE (-5360 3960);
FORCEPROP 2 LASTPIN (-5350 4050) $PN BJ48
J 2
(-5360 4060);
DISPLAY 0.617021 (-5360 4060);
PAINT ORANGE (-5360 4060);
FORCEPROP 2 LASTPIN (-5350 2900) $PN AR20
J 2
(-5360 2910);
DISPLAY 0.617021 (-5360 2910);
PAINT ORANGE (-5360 2910);
FORCEPROP 2 LASTPIN (-5350 3050) $PN AP7
J 2
(-5360 3060);
DISPLAY 0.617021 (-5360 3060);
PAINT ORANGE (-5360 3060);
FORCEPROP 2 LASTPIN (-5350 3000) $PN AR9
J 2
(-5360 3010);
DISPLAY 0.617021 (-5360 3010);
PAINT ORANGE (-5360 3010);
FORCEPROP 2 LASTPIN (-5350 4000) $PN BB52
J 2
(-5360 4010);
DISPLAY 0.617021 (-5360 4010);
PAINT ORANGE (-5360 4010);
FORCEPROP 2 LASTPIN (-2150 2200) $PN BY14
J 0
(-2140 2210);
DISPLAY 0.617021 (-2140 2210);
PAINT ORANGE (-2140 2210);
FORCEPROP 2 LASTPIN (-5350 3250) $PN AU13
J 2
(-5360 3260);
DISPLAY 0.617021 (-5360 3260);
PAINT ORANGE (-5360 3260);
FORCEPROP 2 LASTPIN (-5350 3200) $PN AR13
J 2
(-5360 3210);
DISPLAY 0.617021 (-5360 3210);
PAINT ORANGE (-5360 3210);
FORCEPROP 2 LASTPIN (-5350 3150) $PN AL11
J 2
(-5360 3160);
DISPLAY 0.617021 (-5360 3160);
PAINT ORANGE (-5360 3160);
FORCEPROP 2 LASTPIN (-5350 2750) $PN AL18
J 2
(-5360 2760);
DISPLAY 0.617021 (-5360 2760);
PAINT ORANGE (-5360 2760);
FORCEPROP 2 LASTPIN (-2150 2750) $PN BW24
J 0
(-2140 2760);
DISPLAY 0.617021 (-2140 2760);
PAINT ORANGE (-2140 2760);
FORCEPROP 2 LASTPIN (-5350 2450) $PN AG7
J 2
(-5360 2460);
DISPLAY 0.617021 (-5360 2460);
PAINT ORANGE (-5360 2460);
FORCEPROP 2 LASTPIN (-5350 2500) $PN AK9
J 2
(-5360 2510);
DISPLAY 0.617021 (-5360 2510);
PAINT ORANGE (-5360 2510);
FORCEPROP 2 LASTPIN (-5350 2550) $PN AK20
J 2
(-5360 2560);
DISPLAY 0.617021 (-5360 2560);
PAINT ORANGE (-5360 2560);
FORCEPROP 2 LASTPIN (-5350 1700) $PN BE11
J 2
(-5360 1710);
DISPLAY 0.617021 (-5360 1710);
PAINT ORANGE (-5360 1710);
FORCEPROP 2 LASTPIN (-5350 1650) $PN AV11
J 2
(-5360 1660);
DISPLAY 0.617021 (-5360 1660);
PAINT ORANGE (-5360 1660);
FORCEPROP 2 LASTPIN (-5350 1600) $PN BG11
J 2
(-5360 1610);
DISPLAY 0.617021 (-5360 1610);
PAINT ORANGE (-5360 1610);
FORCEPROP 1 LAST LOCATION U7C1
J 0
(-5300 4550);
DISPLAY 0.617021 (-5300 4550);
PAINT AQUA (-5300 4550);
FORCEPROP 2 LASTPIN (-5350 2200) $PN BA17
J 2
(-5360 2210);
DISPLAY 0.617021 (-5360 2210);
PAINT ORANGE (-5360 2210);
FORCEPROP 2 LASTPIN (-2150 2500) $PN CA20
J 0
(-2140 2510);
DISPLAY 0.617021 (-2140 2510);
PAINT ORANGE (-2140 2510);
FORCEPROP 2 LASTPIN (-5350 2150) $PN BE15
J 2
(-5360 2160);
DISPLAY 0.617021 (-5360 2160);
PAINT ORANGE (-5360 2160);
FORCEPROP 2 LASTPIN (-2150 1650) $PN BM4
J 0
(-2140 1660);
DISPLAY 0.617021 (-2140 1660);
PAINT ORANGE (-2140 1660);
FORCEPROP 2 LASTPIN (-2150 1600) $PN BM2
J 0
(-2140 1610);
DISPLAY 0.617021 (-2140 1610);
PAINT ORANGE (-2140 1610);
FORCEPROP 2 LASTPIN (-2150 1550) $PN CA13
J 0
(-2140 1560);
DISPLAY 0.617021 (-2140 1560);
PAINT ORANGE (-2140 1560);
FORCEPROP 2 LASTPIN (-2150 1500) $PN BU6
J 0
(-2140 1510);
DISPLAY 0.617021 (-2140 1510);
PAINT ORANGE (-2140 1510);
FORCEPROP 2 LASTPIN (-2150 1350) $PN BP4
J 0
(-2140 1360);
DISPLAY 0.617021 (-2140 1360);
PAINT ORANGE (-2140 1360);
FORCEPROP 2 LASTPIN (-2150 2250) $PN BW13
J 0
(-2140 2260);
DISPLAY 0.617021 (-2140 2260);
PAINT ORANGE (-2140 2260);
FORCEPROP 2 LASTPIN (-2150 1300) $PN BK4
J 0
(-2140 1310);
DISPLAY 0.617021 (-2140 1310);
PAINT ORANGE (-2140 1310);
FORCEPROP 2 LASTPIN (-2150 2150) $PN BY10
J 0
(-2140 2160);
DISPLAY 0.617021 (-2140 2160);
PAINT ORANGE (-2140 2160);
FORCEPROP 2 LASTPIN (-2150 2100) $PN CA11
J 0
(-2140 2110);
DISPLAY 0.617021 (-2140 2110);
PAINT ORANGE (-2140 2110);
FORCEPROP 2 LASTPIN (-2150 2050) $PN BV10
J 0
(-2140 2060);
DISPLAY 0.617021 (-2140 2060);
PAINT ORANGE (-2140 2060);
FORCEPROP 2 LASTPIN (-2150 2000) $PN BW9
J 0
(-2140 2010);
DISPLAY 0.617021 (-2140 2010);
PAINT ORANGE (-2140 2010);
FORCEPROP 2 LASTPIN (-2150 1950) $PN BW6
J 0
(-2140 1960);
DISPLAY 0.617021 (-2140 1960);
PAINT ORANGE (-2140 1960);
FORCEPROP 2 LASTPIN (-2150 1900) $PN BW11
J 0
(-2140 1910);
DISPLAY 0.617021 (-2140 1910);
PAINT ORANGE (-2140 1910);
FORCEPROP 2 LASTPIN (-2150 1850) $PN BT5
J 0
(-2140 1860);
DISPLAY 0.617021 (-2140 1860);
PAINT ORANGE (-2140 1860);
FORCEPROP 2 LASTPIN (-2150 1800) $PN BV8
J 0
(-2140 1810);
DISPLAY 0.617021 (-2140 1810);
PAINT ORANGE (-2140 1810);
FORCEPROP 2 LASTPIN (-2150 1250) $PN BL1
J 0
(-2140 1260);
DISPLAY 0.617021 (-2140 1260);
PAINT ORANGE (-2140 1260);
FORCEPROP 2 LASTPIN (-2150 2900) $PN BW22
J 0
(-2140 2910);
DISPLAY 0.617021 (-2140 2910);
PAINT ORANGE (-2140 2910);
FORCEPROP 2 LASTPIN (-2150 2850) $PN CA24
J 0
(-2140 2860);
DISPLAY 0.617021 (-2140 2860);
PAINT ORANGE (-2140 2860);
FORCEPROP 2 LASTPIN (-2150 2800) $PN BV23
J 0
(-2140 2810);
DISPLAY 0.617021 (-2140 2810);
PAINT ORANGE (-2140 2810);
FORCEPROP 2 LASTPIN (-2150 2650) $PN BY23
J 0
(-2140 2660);
DISPLAY 0.617021 (-2140 2660);
PAINT ORANGE (-2140 2660);
FORCEPROP 2 LASTPIN (-2150 2550) $PN BV21
J 0
(-2140 2560);
DISPLAY 0.617021 (-2140 2560);
PAINT ORANGE (-2140 2560);
FORCEPROP 2 LASTPIN (-2150 3500) $PN AV1
J 0
(-2140 3510);
DISPLAY 0.617021 (-2140 3510);
PAINT ORANGE (-2140 3510);
FORCEPROP 2 LASTPIN (-2150 4300) $PN BH4
J 0
(-2140 4310);
DISPLAY 0.617021 (-2140 4310);
PAINT ORANGE (-2140 4310);
FORCEPROP 2 LASTPIN (-2150 4250) $PN BH2
J 0
(-2140 4260);
DISPLAY 0.617021 (-2140 4260);
PAINT ORANGE (-2140 4260);
FORCEPROP 2 LASTPIN (-2150 4200) $PN BA2
J 0
(-2140 4210);
DISPLAY 0.617021 (-2140 4210);
PAINT ORANGE (-2140 4210);
FORCEPROP 2 LASTPIN (-2150 3200) $PN AW4
J 0
(-2140 3210);
DISPLAY 0.617021 (-2140 3210);
PAINT ORANGE (-2140 3210);
FORCEPROP 2 LASTPIN (-2150 4100) $PN BD3
J 0
(-2140 4110);
DISPLAY 0.617021 (-2140 4110);
PAINT ORANGE (-2140 4110);
FORCEPROP 2 LASTPIN (-2150 4050) $PN BC4
J 0
(-2140 4060);
DISPLAY 0.617021 (-2140 4060);
PAINT ORANGE (-2140 4060);
FORCEPROP 2 LASTPIN (-2150 4000) $PN BE4
J 0
(-2140 4010);
DISPLAY 0.617021 (-2140 4010);
PAINT ORANGE (-2140 4010);
FORCEPROP 2 LASTPIN (-2150 3950) $PN BF1
J 0
(-2140 3960);
DISPLAY 0.617021 (-2140 3960);
PAINT ORANGE (-2140 3960);
FORCEPROP 2 LASTPIN (-2150 3900) $PN BB3
J 0
(-2140 3910);
DISPLAY 0.617021 (-2140 3910);
PAINT ORANGE (-2140 3910);
FORCEPROP 2 LASTPIN (-2150 3850) $PN BC2
J 0
(-2140 3860);
DISPLAY 0.617021 (-2140 3860);
PAINT ORANGE (-2140 3860);
FORCEPROP 2 LASTPIN (-2150 3800) $PN AY1
J 0
(-2140 3810);
DISPLAY 0.617021 (-2140 3810);
PAINT ORANGE (-2140 3810);
FORCEPROP 2 LASTPIN (-5350 1400) $PN BA9
J 2
(-5360 1410);
DISPLAY 0.617021 (-5360 1410);
PAINT ORANGE (-5360 1410);
FORCEPROP 2 LASTPIN (-5350 1350) $PN AY7
J 2
(-5360 1360);
DISPLAY 0.617021 (-5360 1360);
PAINT ORANGE (-5360 1360);
FORCEPROP 2 LASTPIN (-5350 1250) $PN AV15
J 2
(-5360 1260);
DISPLAY 0.617021 (-5360 1260);
PAINT ORANGE (-5360 1260);
FORCEPROP 2 LASTPIN (-5350 2050) $PN BD9
J 2
(-5360 2060);
DISPLAY 0.617021 (-5360 2060);
PAINT ORANGE (-5360 2060);
FORCEPROP 2 LASTPIN (-5350 2850) $PN AH9
J 2
(-5360 2860);
DISPLAY 0.617021 (-5360 2860);
PAINT ORANGE (-5360 2860);
FORCEPROP 2 LASTPIN (-5350 3350) $PN AL15
J 2
(-5360 3360);
DISPLAY 0.617021 (-5360 3360);
PAINT ORANGE (-5360 3360);
FORCEPROP 2 LASTPIN (-5350 2950) $PN AL7
J 2
(-5360 2960);
DISPLAY 0.617021 (-5360 2960);
PAINT ORANGE (-5360 2960);
FORCEPROP 2 LASTPIN (-5350 4300) $PN AU58
J 2
(-5360 4310);
DISPLAY 0.617021 (-5360 4310);
PAINT ORANGE (-5360 4310);
FORCEPROP 2 LASTPIN (-5350 4200) $PN BN48
J 2
(-5360 4210);
DISPLAY 0.617021 (-5360 4210);
PAINT ORANGE (-5360 4210);
FORCEPROP 2 LASTPIN (-2150 3050) $PN BY25
J 0
(-2140 3060);
DISPLAY 0.617021 (-2140 3060);
PAINT ORANGE (-2140 3060);
FORCEPROP 2 LASTPIN (-2150 3750) $PN BB1
J 0
(-2140 3760);
DISPLAY 0.617021 (-2140 3760);
PAINT ORANGE (-2140 3760);
FORCEPROP 2 LASTPIN (-2150 3650) $PN BA4
J 0
(-2140 3660);
DISPLAY 0.617021 (-2140 3660);
PAINT ORANGE (-2140 3660);
FORCEPROP 2 LASTPIN (-2150 3600) $PN BE2
J 0
(-2140 3610);
DISPLAY 0.617021 (-2140 3610);
PAINT ORANGE (-2140 3610);
FORCEPROP 2 LASTPIN (-2150 3700) $PN BD1
J 0
(-2140 3710);
DISPLAY 0.617021 (-2140 3710);
PAINT ORANGE (-2140 3710);
FORCEPROP 2 LASTPIN (-2150 1700) $PN BN3
J 0
(-2140 1710);
DISPLAY 0.617021 (-2140 1710);
PAINT ORANGE (-2140 1710);
FORCEPROP 2 LASTPIN (-2150 1750) $PN BW5
J 0
(-2140 1760);
DISPLAY 0.617021 (-2140 1760);
PAINT ORANGE (-2140 1760);
FORCEPROP 2 LASTPIN (-2150 4150) $PN BF3
J 0
(-2140 4160);
DISPLAY 0.617021 (-2140 4160);
PAINT ORANGE (-2140 4160);
FORCEPROP 2 LASTPIN (-2150 2400) $PN BV14
J 0
(-2140 2410);
DISPLAY 0.617021 (-2140 2410);
PAINT ORANGE (-2140 2410);
FORCEPROP 2 LASTPIN (-5350 1300) $PN BE22
J 2
(-5360 1310);
DISPLAY 0.617021 (-5360 1310);
PAINT ORANGE (-5360 1310);
FORCEPROP 2 LASTPIN (-5350 1200) $PN AY11
J 2
(-5360 1210);
DISPLAY 0.617021 (-5360 1210);
PAINT ORANGE (-5360 1210);
FORCEPROP 1 LAST PART_NUMBER H91415-002
J 0
(-5300 1000);
DISPLAY 0.617021 (-5300 1000);
PAINT BLUE (-5300 1000);
FORCEPROP 2 LASTPIN (-2150 3550) $PN AR3
J 0
(-2140 3560);
DISPLAY 0.617021 (-2140 3560);
PAINT ORANGE (-2140 3560);
FORCEPROP 2 LASTPIN (-2150 3400) $PN AY3
J 0
(-2140 3410);
DISPLAY 0.617021 (-2140 3410);
PAINT ORANGE (-2140 3410);
FORCEPROP 2 LASTPIN (-2150 3250) $PN AV3
J 0
(-2140 3260);
DISPLAY 0.617021 (-2140 3260);
PAINT ORANGE (-2140 3260);
FORCEPROP 2 LASTPIN (-5350 2300) $PN BD20
J 2
(-5360 2310);
DISPLAY 0.617021 (-5360 2310);
PAINT ORANGE (-5360 2310);
FORCEPROP 2 LASTPIN (-5350 2250) $PN BG7
J 2
(-5360 2260);
DISPLAY 0.617021 (-5360 2260);
PAINT ORANGE (-5360 2260);
FORCEPROP 2 LASTPIN (-5350 2100) $PN BE7
J 2
(-5360 2110);
DISPLAY 0.617021 (-5360 2110);
PAINT ORANGE (-5360 2110);
FORCEPROP 2 LASTPIN (-5350 2000) $PN BD17
J 2
(-5360 2010);
DISPLAY 0.617021 (-5360 2010);
PAINT ORANGE (-5360 2010);
FORCEPROP 2 LASTPIN (-5350 1950) $PN BE18
J 2
(-5360 1960);
DISPLAY 0.617021 (-5360 1960);
PAINT ORANGE (-5360 1960);
FORCEPROP 2 LASTPIN (-5350 1850) $PN AY18
J 2
(-5360 1860);
DISPLAY 0.617021 (-5360 1860);
PAINT ORANGE (-5360 1860);
FORCEPROP 2 LASTPIN (-5350 1750) $PN BA20
J 2
(-5360 1760);
DISPLAY 0.617021 (-5360 1760);
PAINT ORANGE (-5360 1760);
FORCEPROP 2 LASTPIN (-5350 1550) $PN AY15
J 2
(-5360 1560);
DISPLAY 0.617021 (-5360 1560);
PAINT ORANGE (-5360 1560);
FORCEPROP 2 LASTPIN (-5350 1500) $PN AV18
J 2
(-5360 1510);
DISPLAY 0.617021 (-5360 1510);
PAINT ORANGE (-5360 1510);
FORCEPROP 2 LASTPIN (-5350 1450) $PN AW20
J 2
(-5360 1460);
DISPLAY 0.617021 (-5360 1460);
PAINT ORANGE (-5360 1460);
FORCEPROP 2 LASTPIN (-2150 2950) $PN BY21
J 0
(-2140 2960);
DISPLAY 0.617021 (-2140 2960);
PAINT ORANGE (-2140 2960);
FORCEPROP 2 LASTPIN (-2150 3000) $PN BV25
J 0
(-2140 3010);
DISPLAY 0.617021 (-2140 3010);
PAINT ORANGE (-2140 3010);
FORCEPROP 2 LASTPIN (-2150 3300) $PN AR1
J 0
(-2140 3310);
DISPLAY 0.617021 (-2140 3310);
PAINT ORANGE (-2140 3310);
FORCEPROP 2 LASTPIN (-2150 3150) $PN AT4
J 0
(-2140 3160);
DISPLAY 0.617021 (-2140 3160);
PAINT ORANGE (-2140 3160);
FORCEPROP 2 LASTPIN (-2150 3450) $PN AW2
J 0
(-2140 3460);
DISPLAY 0.617021 (-2140 3460);
PAINT ORANGE (-2140 3460);
FORCEPROP 2 LASTPIN (-5350 3100) $PN AP11
J 2
(-5360 3110);
DISPLAY 0.617021 (-5360 3110);
PAINT ORANGE (-5360 3110);
FORCEPROP 2 LASTPIN (-2150 2600) $PN CA22
J 0
(-2140 2610);
DISPLAY 0.617021 (-2140 2610);
PAINT ORANGE (-2140 2610);
FORCEPROP 2 LASTPIN (-2150 3350) $PN AT2
J 0
(-2140 3360);
DISPLAY 0.617021 (-2140 3360);
PAINT ORANGE (-2140 3360);
FORCEPROP 2 LASTPIN (-5350 3400) $PN AU9
J 2
(-5360 3410);
DISPLAY 0.617021 (-5360 3410);
PAINT ORANGE (-5360 3410);
FORCEPROP 2 LASTPIN (-5350 2350) $PN BA13
J 2
(-5360 2360);
DISPLAY 0.617021 (-5360 2360);
PAINT ORANGE (-5360 2360);
FORCEPROP 2 LASTPIN (-5350 2800) $PN AK17
J 2
(-5360 2810);
DISPLAY 0.617021 (-5360 2810);
PAINT ORANGE (-5360 2810);
FORCEPROP 2 LASTPIN (-5350 3300) $PN AP15
J 2
(-5360 3310);
DISPLAY 0.617021 (-5360 3310);
PAINT ORANGE (-5360 3310);
FORCEPROP 2 LASTPIN (-2150 2700) $PN BW20
J 0
(-2140 2710);
DISPLAY 0.617021 (-2140 2710);
PAINT ORANGE (-2140 2710);
FORCEPROP 2 LASTPIN (-5350 2650) $PN AH13
J 2
(-5360 2660);
DISPLAY 0.617021 (-5360 2660);
PAINT ORANGE (-5360 2660);
FORCEPROP 2 LASTPIN (-5350 1900) $PN AV7
J 2
(-5360 1910);
DISPLAY 0.617021 (-5360 1910);
PAINT ORANGE (-5360 1910);
FORCEPROP 2 LASTPIN (-2150 2350) $PN BY12
J 0
(-2140 2360);
DISPLAY 0.617021 (-2140 2360);
PAINT ORANGE (-2140 2360);
FORCEPROP 2 LASTPIN (-2150 2300) $PN BV12
J 0
(-2140 2310);
DISPLAY 0.617021 (-2140 2310);
PAINT ORANGE (-2140 2310);
FORCEPROP 2 LASTPIN (-5350 2700) $PN AH17
J 2
(-5360 2710);
DISPLAY 0.617021 (-5360 2710);
PAINT ORANGE (-5360 2710);
FORCEPROP 2 LASTPIN (-2150 1450) $PN BL3
J 0
(-2140 1460);
DISPLAY 0.617021 (-2140 1460);
PAINT ORANGE (-2140 1460);
FORCEPROP 2 LASTPIN (-5350 4250) $PN AW54
J 2
(-5360 4260);
DISPLAY 0.617021 (-5360 4260);
PAINT ORANGE (-5360 4260);
FORCEPROP 2 LASTPIN (-5350 4100) $PN AV56
J 2
(-5360 4110);
DISPLAY 0.617021 (-5360 4110);
PAINT ORANGE (-5360 4110);
FORCEPROP 2 LASTPIN (-5350 3900) $PN AV52
J 2
(-5360 3910);
DISPLAY 0.617021 (-5360 3910);
PAINT ORANGE (-5360 3910);
FORCEPROP 2 LASTPIN (-5350 3800) $PN BG52
J 2
(-5360 3810);
DISPLAY 0.617021 (-5360 3810);
PAINT ORANGE (-5360 3810);
FORCEPROP 2 LASTPIN (-5350 3700) $PN BH50
J 2
(-5360 3710);
DISPLAY 0.617021 (-5360 3710);
PAINT ORANGE (-5360 3710);
FORCEPROP 2 LASTPIN (-5350 3550) $PN AP18
J 2
(-5360 3560);
DISPLAY 0.617021 (-5360 3560);
PAINT ORANGE (-5360 3560);
FORCEPROP 2 LASTPIN (-5350 3500) $PN AR17
J 2
(-5360 3510);
DISPLAY 0.617021 (-5360 3510);
PAINT ORANGE (-5360 3510);
FORCEPROP 2 LASTPIN (-5350 3450) $PN AU20
J 2
(-5360 3460);
DISPLAY 0.617021 (-5360 3460);
PAINT ORANGE (-5360 3460);
FORCEPROP 2 LASTPIN (-5350 3850) $PN BE52
J 2
(-5360 3860);
DISPLAY 0.617021 (-5360 3860);
PAINT ORANGE (-5360 3860);
FORCEPROP 2 LASTPIN (-5350 3600) $PN AU17
J 2
(-5360 3610);
DISPLAY 0.617021 (-5360 3610);
PAINT ORANGE (-5360 3610);
FORCEPROP 1 LAST MATERIAL IC
J 0
(-5300 4500);
DISPLAY 0.617021 (-5300 4500);
PAINT SKYBLUE (-5300 4500);
FORCEPROP 1 LAST PATH I147
J 0
(-3750 4500);
PAINT GREEN (-3750 4500);
DISPLAY INVISIBLE (-3750 4500);
FORCEPROP 2 LAST CDS_LOCATION U7C1
J 0
(-5300 4550);
DISPLAY 0.617021 (-5300 4550);
PAINT AQUA (-5300 4550);
DISPLAY INVISIBLE (-5300 4550);
FORCEPROP 0 LAST BOM_COST SB
J 0
(-4200 4950);
DISPLAY 1.361702 (-4200 4950);
PAINT ORANGE (-4200 4950);
DISPLAY INVISIBLE (-4200 4950);
FORCEPROP 2 LAST CDS_LIB mstr_u_proc
J 0
(-3750 2800);
PAINT ORANGE (-3750 2800);
DISPLAY INVISIBLE (-3750 2800);
FORCEPROP 2 LAST SEC 7
J 0
(-5300 4600);
DISPLAY 0.680851 (-5300 4600);
PAINT MONO (-5300 4600);
DISPLAY INVISIBLE (-5300 4600);
FORCEPROP 2 LAST SEC_TYPE BGA1
J 0
(-5300 4600);
DISPLAY 1.021277 (-5300 4600);
PAINT ORANGE (-5300 4600);
DISPLAY INVISIBLE (-5300 4600);
FORCEPROP 0 LAST ROOM SB
J 0
(-4200 4850);
DISPLAY 1.361702 (-4200 4850);
PAINT ORANGE (-4200 4850);
DISPLAY INVISIBLE (-4200 4850);
FORCEPROP 1 LAST PACK_TYPE BGA1
J 0
(-5300 4600);
PAINT SKYBLUE (-5300 4600);
DISPLAY INVISIBLE (-5300 4600);
FORCEADD OFFPAGE..5
R 2
(-1100 3650);
FORCEPROP 2 LAST $XR0 138 
J 0
(-881 3650);
DISPLAY 0.638298 (-881 3650);
PAINT MONO (-881 3650);
FORCEPROP 2 LAST PATH I15
J 0
(-900 3725);
DISPLAY 1.021277 (-900 3725);
PAINT ORANGE (-900 3725);
DISPLAY INVISIBLE (-900 3725);
FORCEPROP 1 LAST COMMENT_BODY TRUE
J 2
(-1200 3575);
DISPLAY 0.872340 (-1200 3575);
PAINT GREEN (-1200 3575);
DISPLAY INVISIBLE (-1200 3575);
FORCEPROP 1 LAST OFFPAGE TRUE
J 2
(-1425 3525);
DISPLAY 0.872340 (-1425 3525);
PAINT GREEN (-1425 3525);
DISPLAY INVISIBLE (-1425 3525);
FORCEPROP 2 LAST CDS_LIB mstr_standard
J 2
(-1100 3650);
DISPLAY 1.212766 (-1100 3650);
PAINT ORANGE (-1100 3650);
DISPLAY INVISIBLE (-1100 3650);
FORCEADD OFFPAGE..1
(-7425 4150);
FORCEPROP 2 LAST $XR1 190 
J 0
(-7827 4150);
DISPLAY 0.638298 (-7827 4150);
PAINT MONO (-7827 4150);
FORCEPROP 2 LAST $XR0 176 
J 0
(-7707 4150);
DISPLAY 0.638298 (-7707 4150);
PAINT MONO (-7707 4150);
FORCEPROP 2 LAST PATH I150
J 0
(-7700 4200);
DISPLAY 1.021277 (-7700 4200);
PAINT ORANGE (-7700 4200);
DISPLAY INVISIBLE (-7700 4200);
FORCEPROP 1 LAST COMMENT_BODY TRUE
J 0
(-7300 4050);
DISPLAY 1.404255 (-7300 4050);
PAINT PEACH (-7300 4050);
DISPLAY INVISIBLE (-7300 4050);
FORCEPROP 1 LAST OFFPAGE TRUE
J 0
(-7100 4025);
PAINT GREEN (-7100 4025);
DISPLAY INVISIBLE (-7100 4025);
FORCEPROP 2 LAST CDS_LIB mstr_standard
J 0
(-7425 4150);
DISPLAY 1.212766 (-7425 4150);
PAINT ORANGE (-7425 4150);
DISPLAY INVISIBLE (-7425 4150);
FORCEADD OFFPAGE..4
(-1325 2850);
FORCEPROP 2 LAST $XR0 189 
J 0
(-1139 2850);
DISPLAY 0.638298 (-1139 2850);
PAINT MONO (-1139 2850);
FORCEPROP 2 LAST CDS_LIB mstr_standard
J 0
(-1325 2850);
PAINT ORANGE (-1325 2850);
DISPLAY INVISIBLE (-1325 2850);
FORCEPROP 1 LAST OFFPAGE TRUE
J 0
(-1000 2725);
DISPLAY 0.872340 (-1000 2725);
PAINT GREEN (-1000 2725);
DISPLAY INVISIBLE (-1000 2725);
FORCEPROP 1 LAST COMMENT_BODY TRUE
J 0
(-1350 2750);
DISPLAY 0.872340 (-1350 2750);
PAINT GREEN (-1350 2750);
DISPLAY INVISIBLE (-1350 2750);
FORCEPROP 2 LAST PATH I151
J 0
(-1150 2925);
DISPLAY 1.021277 (-1150 2925);
PAINT ORANGE (-1150 2925);
DISPLAY INVISIBLE (-1150 2925);
FORCEADD OFFPAGE..1
(-7425 4050);
FORCEPROP 2 LAST $XR3 191 
J 0
(-7916 4014);
DISPLAY 0.638298 (-7916 4014);
PAINT MONO (-7916 4014);
FORCEPROP 2 LAST $XR2 157 
J 0
(-7916 4050);
DISPLAY 0.638298 (-7916 4050);
PAINT MONO (-7916 4050);
FORCEPROP 2 LAST $XR1 156 
J 0
(-7796 4050);
DISPLAY 0.638298 (-7796 4050);
PAINT MONO (-7796 4050);
FORCEPROP 2 LAST $XR0 89 
J 0
(-7676 4050);
DISPLAY 0.638298 (-7676 4050);
PAINT MONO (-7676 4050);
FORCEPROP 2 LAST PATH I152
J 0
(-7375 4125);
DISPLAY 1.021277 (-7375 4125);
PAINT ORANGE (-7375 4125);
DISPLAY INVISIBLE (-7375 4125);
FORCEPROP 1 LAST COMMENT_BODY TRUE
J 0
(-7300 3950);
DISPLAY 1.404255 (-7300 3950);
PAINT PEACH (-7300 3950);
DISPLAY INVISIBLE (-7300 3950);
FORCEPROP 1 LAST OFFPAGE TRUE
J 0
(-7100 3925);
PAINT GREEN (-7100 3925);
DISPLAY INVISIBLE (-7100 3925);
FORCEPROP 2 LAST CDS_LIB mstr_standard
J 0
(-7425 4050);
PAINT ORANGE (-7425 4050);
DISPLAY INVISIBLE (-7425 4050);
FORCEADD OFFPAGE..1
(-7425 3900);
FORCEPROP 2 LAST $XR1 144 
J 0
(-7856 3900);
DISPLAY 0.638298 (-7856 3900);
PAINT MONO (-7856 3900);
FORCEPROP 2 LAST $XR0 92 
J 0
(-7736 3900);
DISPLAY 0.638298 (-7736 3900);
PAINT MONO (-7736 3900);
FORCEPROP 2 LAST PATH I154
J 0
(-7375 3975);
DISPLAY 1.021277 (-7375 3975);
PAINT ORANGE (-7375 3975);
DISPLAY INVISIBLE (-7375 3975);
FORCEPROP 1 LAST COMMENT_BODY TRUE
J 0
(-7300 3800);
DISPLAY 0.872340 (-7300 3800);
PAINT GREEN (-7300 3800);
DISPLAY INVISIBLE (-7300 3800);
FORCEPROP 1 LAST OFFPAGE TRUE
J 0
(-7100 3775);
DISPLAY 0.872340 (-7100 3775);
PAINT GREEN (-7100 3775);
DISPLAY INVISIBLE (-7100 3775);
FORCEPROP 2 LAST CDS_LIB mstr_standard
J 0
(-7425 3900);
PAINT MONO (-7425 3900);
DISPLAY INVISIBLE (-7425 3900);
FORCEADD OFFPAGE..5
(-7425 4200);
FORCEPROP 2 LAST $XR2 119 
J 0
(-7920 4200);
DISPLAY 0.638298 (-7920 4200);
PAINT MONO (-7920 4200);
FORCEPROP 2 LAST $XR1 146 
J 0
(-7800 4200);
DISPLAY 0.638298 (-7800 4200);
PAINT MONO (-7800 4200);
FORCEPROP 2 LAST $XR0 133 
J 0
(-7680 4200);
DISPLAY 0.638298 (-7680 4200);
PAINT MONO (-7680 4200);
FORCEPROP 2 LAST PATH I155
J 0
(-7375 4275);
DISPLAY 1.021277 (-7375 4275);
PAINT ORANGE (-7375 4275);
DISPLAY INVISIBLE (-7375 4275);
FORCEPROP 1 LAST COMMENT_BODY TRUE
J 0
(-7325 4125);
DISPLAY 1.404255 (-7325 4125);
PAINT PEACH (-7325 4125);
DISPLAY INVISIBLE (-7325 4125);
FORCEPROP 1 LAST OFFPAGE TRUE
J 0
(-7100 4075);
PAINT GREEN (-7100 4075);
DISPLAY INVISIBLE (-7100 4075);
FORCEPROP 2 LAST CDS_LIB mstr_standard
J 0
(-7425 4200);
PAINT MONO (-7425 4200);
DISPLAY INVISIBLE (-7425 4200);
FORCEADD OFFPAGE..5
(-7425 4250);
FORCEPROP 2 LAST $XR2 119 
J 0
(-7920 4250);
DISPLAY 0.638298 (-7920 4250);
PAINT MONO (-7920 4250);
FORCEPROP 2 LAST $XR1 144 
J 0
(-7800 4250);
DISPLAY 0.638298 (-7800 4250);
PAINT MONO (-7800 4250);
FORCEPROP 2 LAST $XR0 133 
J 0
(-7680 4250);
DISPLAY 0.638298 (-7680 4250);
PAINT MONO (-7680 4250);
FORCEPROP 2 LAST PATH I156
J 0
(-7375 4325);
DISPLAY 1.021277 (-7375 4325);
PAINT ORANGE (-7375 4325);
DISPLAY INVISIBLE (-7375 4325);
FORCEPROP 1 LAST COMMENT_BODY TRUE
J 0
(-7325 4175);
DISPLAY 1.404255 (-7325 4175);
PAINT PEACH (-7325 4175);
DISPLAY INVISIBLE (-7325 4175);
FORCEPROP 1 LAST OFFPAGE TRUE
J 0
(-7100 4125);
PAINT GREEN (-7100 4125);
DISPLAY INVISIBLE (-7100 4125);
FORCEPROP 2 LAST CDS_LIB mstr_standard
J 0
(-7425 4250);
PAINT MONO (-7425 4250);
DISPLAY INVISIBLE (-7425 4250);
FORCEADD OFFPAGE..1
(-7425 4300);
FORCEPROP 2 LAST $XR2 170 
J 0
(-7917 4300);
DISPLAY 0.638298 (-7917 4300);
PAINT MONO (-7917 4300);
FORCEPROP 2 LAST $XR1 145 
J 0
(-7797 4300);
DISPLAY 0.638298 (-7797 4300);
PAINT MONO (-7797 4300);
FORCEPROP 2 LAST $XR0 200 
J 0
(-7677 4300);
DISPLAY 0.638298 (-7677 4300);
PAINT MONO (-7677 4300);
FORCEPROP 2 LAST PATH I157
J 0
(-7375 4375);
DISPLAY 1.021277 (-7375 4375);
PAINT ORANGE (-7375 4375);
DISPLAY INVISIBLE (-7375 4375);
FORCEPROP 1 LAST COMMENT_BODY TRUE
J 0
(-7300 4200);
DISPLAY 1.404255 (-7300 4200);
PAINT PEACH (-7300 4200);
DISPLAY INVISIBLE (-7300 4200);
FORCEPROP 1 LAST OFFPAGE TRUE
J 0
(-7100 4175);
PAINT GREEN (-7100 4175);
DISPLAY INVISIBLE (-7100 4175);
FORCEPROP 2 LAST CDS_LIB mstr_standard
J 0
(-7425 4300);
PAINT MONO (-7425 4300);
DISPLAY INVISIBLE (-7425 4300);
FORCEADD OFFPAGE..1
(-6275 2450);
FORCEPROP 2 LAST $XR1 145 
J 0
(-6677 2450);
DISPLAY 0.638298 (-6677 2450);
PAINT MONO (-6677 2450);
FORCEPROP 2 LAST $XR0 200 
J 0
(-6557 2450);
DISPLAY 0.638298 (-6557 2450);
PAINT MONO (-6557 2450);
FORCEPROP 2 LAST PATH I158
J 0
(-6225 2525);
DISPLAY 1.021277 (-6225 2525);
PAINT ORANGE (-6225 2525);
DISPLAY INVISIBLE (-6225 2525);
FORCEPROP 1 LAST COMMENT_BODY TRUE
J 0
(-6150 2350);
DISPLAY 1.404255 (-6150 2350);
PAINT PEACH (-6150 2350);
DISPLAY INVISIBLE (-6150 2350);
FORCEPROP 1 LAST OFFPAGE TRUE
J 0
(-5950 2325);
PAINT GREEN (-5950 2325);
DISPLAY INVISIBLE (-5950 2325);
FORCEPROP 2 LAST CDS_LIB mstr_standard
J 0
(-6275 2450);
PAINT MONO (-6275 2450);
DISPLAY INVISIBLE (-6275 2450);
FORCEADD OFFPAGE..1
(-6275 2500);
FORCEPROP 2 LAST $XR2 170 
J 0
(-6797 2500);
DISPLAY 0.638298 (-6797 2500);
PAINT MONO (-6797 2500);
FORCEPROP 2 LAST $XR1 145 
J 0
(-6677 2500);
DISPLAY 0.638298 (-6677 2500);
PAINT MONO (-6677 2500);
FORCEPROP 2 LAST $XR0 200 
J 0
(-6557 2500);
DISPLAY 0.638298 (-6557 2500);
PAINT MONO (-6557 2500);
FORCEPROP 2 LAST PATH I159
J 0
(-6225 2575);
DISPLAY 1.021277 (-6225 2575);
PAINT ORANGE (-6225 2575);
DISPLAY INVISIBLE (-6225 2575);
FORCEPROP 1 LAST COMMENT_BODY TRUE
J 0
(-6150 2400);
DISPLAY 1.404255 (-6150 2400);
PAINT PEACH (-6150 2400);
DISPLAY INVISIBLE (-6150 2400);
FORCEPROP 1 LAST OFFPAGE TRUE
J 0
(-5950 2375);
PAINT GREEN (-5950 2375);
DISPLAY INVISIBLE (-5950 2375);
FORCEPROP 2 LAST CDS_LIB mstr_standard
J 0
(-6275 2500);
PAINT MONO (-6275 2500);
DISPLAY INVISIBLE (-6275 2500);
FORCEADD OFFPAGE..5
R 2
(-1100 3200);
FORCEPROP 2 LAST $XR1 154 
J 0
(-791 3200);
DISPLAY 0.638298 (-791 3200);
PAINT MONO (-791 3200);
FORCEPROP 2 LAST $XR0 147 
J 0
(-911 3200);
DISPLAY 0.638298 (-911 3200);
PAINT MONO (-911 3200);
FORCEPROP 2 LAST PATH I16
J 0
(-925 3275);
DISPLAY 1.021277 (-925 3275);
PAINT ORANGE (-925 3275);
DISPLAY INVISIBLE (-925 3275);
FORCEPROP 1 LAST COMMENT_BODY TRUE
J 2
(-1200 3125);
DISPLAY 0.872340 (-1200 3125);
PAINT GREEN (-1200 3125);
DISPLAY INVISIBLE (-1200 3125);
FORCEPROP 1 LAST OFFPAGE TRUE
J 2
(-1425 3075);
DISPLAY 0.872340 (-1425 3075);
PAINT GREEN (-1425 3075);
DISPLAY INVISIBLE (-1425 3075);
FORCEPROP 2 LAST CDS_LIB mstr_standard
J 2
(-1100 3200);
DISPLAY 1.212766 (-1100 3200);
PAINT ORANGE (-1100 3200);
DISPLAY INVISIBLE (-1100 3200);
FORCEADD OFFPAGE..1
(-6275 2550);
FORCEPROP 2 LAST $XR3 190 
J 0
(-6917 2550);
DISPLAY 0.638298 (-6917 2550);
PAINT MONO (-6917 2550);
FORCEPROP 2 LAST $XR2 144 
J 0
(-6797 2550);
DISPLAY 0.638298 (-6797 2550);
PAINT MONO (-6797 2550);
FORCEPROP 2 LAST $XR1 181 
J 0
(-6677 2550);
DISPLAY 0.638298 (-6677 2550);
PAINT MONO (-6677 2550);
FORCEPROP 2 LAST $XR0 157 
J 0
(-6557 2550);
DISPLAY 0.638298 (-6557 2550);
PAINT MONO (-6557 2550);
FORCEPROP 2 LAST PATH I160
J 0
(-6225 2625);
DISPLAY 1.021277 (-6225 2625);
PAINT ORANGE (-6225 2625);
DISPLAY INVISIBLE (-6225 2625);
FORCEPROP 1 LAST COMMENT_BODY TRUE
J 0
(-6150 2450);
DISPLAY 1.404255 (-6150 2450);
PAINT PEACH (-6150 2450);
DISPLAY INVISIBLE (-6150 2450);
FORCEPROP 1 LAST OFFPAGE TRUE
J 0
(-5950 2425);
PAINT GREEN (-5950 2425);
DISPLAY INVISIBLE (-5950 2425);
FORCEPROP 2 LAST CDS_LIB mstr_standard
J 0
(-6275 2550);
PAINT MONO (-6275 2550);
DISPLAY INVISIBLE (-6275 2550);
FORCEADD OFFPAGE..1
(-6275 2600);
FORCEPROP 2 LAST $XR2 181 
J 0
(-6797 2600);
DISPLAY 0.638298 (-6797 2600);
PAINT MONO (-6797 2600);
FORCEPROP 2 LAST $XR1 157 
J 0
(-6677 2600);
DISPLAY 0.638298 (-6677 2600);
PAINT MONO (-6677 2600);
FORCEPROP 2 LAST $XR0 146 
J 0
(-6557 2600);
DISPLAY 0.638298 (-6557 2600);
PAINT MONO (-6557 2600);
FORCEPROP 2 LAST PATH I161
J 0
(-6225 2675);
DISPLAY 1.021277 (-6225 2675);
PAINT ORANGE (-6225 2675);
DISPLAY INVISIBLE (-6225 2675);
FORCEPROP 1 LAST COMMENT_BODY TRUE
J 0
(-6150 2500);
DISPLAY 1.404255 (-6150 2500);
PAINT PEACH (-6150 2500);
DISPLAY INVISIBLE (-6150 2500);
FORCEPROP 1 LAST OFFPAGE TRUE
J 0
(-5950 2475);
PAINT GREEN (-5950 2475);
DISPLAY INVISIBLE (-5950 2475);
FORCEPROP 2 LAST CDS_LIB mstr_standard
J 0
(-6275 2600);
PAINT MONO (-6275 2600);
DISPLAY INVISIBLE (-6275 2600);
FORCEADD OFFPAGE..1
(-6275 3350);
FORCEPROP 2 LAST $XR1 145 
J 0
(-6677 3350);
DISPLAY 0.638298 (-6677 3350);
PAINT MONO (-6677 3350);
FORCEPROP 2 LAST $XR0 191 
J 0
(-6557 3350);
DISPLAY 0.638298 (-6557 3350);
PAINT MONO (-6557 3350);
FORCEPROP 2 LAST PATH I162
J 0
(-6225 3425);
DISPLAY 1.021277 (-6225 3425);
PAINT ORANGE (-6225 3425);
DISPLAY INVISIBLE (-6225 3425);
FORCEPROP 1 LAST COMMENT_BODY TRUE
J 0
(-6150 3250);
DISPLAY 1.404255 (-6150 3250);
PAINT PEACH (-6150 3250);
DISPLAY INVISIBLE (-6150 3250);
FORCEPROP 1 LAST OFFPAGE TRUE
J 0
(-5950 3225);
PAINT GREEN (-5950 3225);
DISPLAY INVISIBLE (-5950 3225);
FORCEPROP 2 LAST CDS_LIB mstr_standard
J 0
(-6275 3350);
PAINT MONO (-6275 3350);
DISPLAY INVISIBLE (-6275 3350);
FORCEADD OFFPAGE..5
(-7350 2650);
FORCEPROP 2 LAST $XR3 182 
J 0
(-7965 2650);
DISPLAY 0.638298 (-7965 2650);
PAINT MONO (-7965 2650);
FORCEPROP 2 LAST $XR2 119 
J 0
(-7845 2650);
DISPLAY 0.638298 (-7845 2650);
PAINT MONO (-7845 2650);
FORCEPROP 2 LAST $XR1 146 
J 0
(-7725 2650);
DISPLAY 0.638298 (-7725 2650);
PAINT MONO (-7725 2650);
FORCEPROP 2 LAST $XR0 133 
J 0
(-7605 2650);
DISPLAY 0.638298 (-7605 2650);
PAINT MONO (-7605 2650);
FORCEPROP 2 LAST CDS_LIB mstr_standard
J 0
(-7350 2650);
PAINT MONO (-7350 2650);
DISPLAY INVISIBLE (-7350 2650);
FORCEPROP 1 LAST OFFPAGE TRUE
J 0
(-7025 2525);
PAINT GREEN (-7025 2525);
DISPLAY INVISIBLE (-7025 2525);
FORCEPROP 1 LAST COMMENT_BODY TRUE
J 0
(-7250 2575);
DISPLAY 1.404255 (-7250 2575);
PAINT PEACH (-7250 2575);
DISPLAY INVISIBLE (-7250 2575);
FORCEPROP 2 LAST PATH I163
J 0
(-7300 2725);
DISPLAY 1.021277 (-7300 2725);
PAINT ORANGE (-7300 2725);
DISPLAY INVISIBLE (-7300 2725);
FORCEADD OFFPAGE..5
(-6275 3300);
FORCEPROP 2 LAST $XR2 157 
J 0
(-6770 3300);
DISPLAY 0.638298 (-6770 3300);
PAINT MONO (-6770 3300);
FORCEPROP 2 LAST $XR1 145 
J 0
(-6650 3300);
DISPLAY 0.638298 (-6650 3300);
PAINT MONO (-6650 3300);
FORCEPROP 2 LAST $XR0 136 
J 0
(-6530 3300);
DISPLAY 0.638298 (-6530 3300);
PAINT MONO (-6530 3300);
FORCEPROP 2 LAST PATH I164
J 0
(-6225 3375);
DISPLAY 1.021277 (-6225 3375);
PAINT ORANGE (-6225 3375);
DISPLAY INVISIBLE (-6225 3375);
FORCEPROP 1 LAST COMMENT_BODY TRUE
J 0
(-6175 3225);
DISPLAY 1.404255 (-6175 3225);
PAINT PEACH (-6175 3225);
DISPLAY INVISIBLE (-6175 3225);
FORCEPROP 1 LAST OFFPAGE TRUE
J 0
(-5950 3175);
PAINT GREEN (-5950 3175);
DISPLAY INVISIBLE (-5950 3175);
FORCEPROP 2 LAST CDS_LIB mstr_standard
J 0
(-6275 3300);
PAINT MONO (-6275 3300);
DISPLAY INVISIBLE (-6275 3300);
FORCEADD OFFPAGE..5
(-6275 3400);
FORCEPROP 2 LAST $XR0 138 
J 0
(-6560 3400);
DISPLAY 0.638298 (-6560 3400);
PAINT MONO (-6560 3400);
FORCEPROP 2 LAST PATH I165
J 0
(-6225 3475);
DISPLAY 1.021277 (-6225 3475);
PAINT ORANGE (-6225 3475);
DISPLAY INVISIBLE (-6225 3475);
FORCEPROP 1 LAST COMMENT_BODY TRUE
J 0
(-6175 3325);
DISPLAY 1.404255 (-6175 3325);
PAINT PEACH (-6175 3325);
DISPLAY INVISIBLE (-6175 3325);
FORCEPROP 1 LAST OFFPAGE TRUE
J 0
(-5950 3275);
PAINT GREEN (-5950 3275);
DISPLAY INVISIBLE (-5950 3275);
FORCEPROP 2 LAST CDS_LIB mstr_standard
J 0
(-6275 3400);
PAINT MONO (-6275 3400);
DISPLAY INVISIBLE (-6275 3400);
FORCEADD OFFPAGE..6
(-6275 3450);
FORCEPROP 2 LAST $XR0 138 
J 0
(-6555 3450);
DISPLAY 0.638298 (-6555 3450);
PAINT MONO (-6555 3450);
FORCEPROP 2 LAST PATH I166
J 0
(-6225 3525);
DISPLAY 1.021277 (-6225 3525);
PAINT ORANGE (-6225 3525);
DISPLAY INVISIBLE (-6225 3525);
FORCEPROP 1 LAST COMMENT_BODY TRUE
J 0
(-6175 3375);
DISPLAY 0.872340 (-6175 3375);
PAINT GREEN (-6175 3375);
DISPLAY INVISIBLE (-6175 3375);
FORCEPROP 1 LAST OFFPAGE TRUE
J 0
(-5950 3325);
DISPLAY 0.872340 (-5950 3325);
PAINT GREEN (-5950 3325);
DISPLAY INVISIBLE (-5950 3325);
FORCEPROP 2 LAST CDS_LIB mstr_standard
J 0
(-6275 3450);
PAINT MONO (-6275 3450);
DISPLAY INVISIBLE (-6275 3450);
FORCEADD OFFPAGE..1
(-6975 2350);
FORCEPROP 2 LAST $XR2 158 
J 0
(-7467 2350);
DISPLAY 0.638298 (-7467 2350);
PAINT MONO (-7467 2350);
FORCEPROP 2 LAST $XR1 144 
J 0
(-7347 2350);
DISPLAY 0.638298 (-7347 2350);
PAINT MONO (-7347 2350);
FORCEPROP 2 LAST $XR0 190 
J 0
(-7227 2350);
DISPLAY 0.638298 (-7227 2350);
PAINT MONO (-7227 2350);
FORCEPROP 2 LAST CDS_LIB mstr_standard
J 0
(-6975 2350);
PAINT MONO (-6975 2350);
DISPLAY INVISIBLE (-6975 2350);
FORCEPROP 1 LAST OFFPAGE TRUE
J 0
(-6650 2225);
PAINT GREEN (-6650 2225);
DISPLAY INVISIBLE (-6650 2225);
FORCEPROP 1 LAST COMMENT_BODY TRUE
J 0
(-6850 2250);
DISPLAY 1.404255 (-6850 2250);
PAINT PEACH (-6850 2250);
DISPLAY INVISIBLE (-6850 2250);
FORCEPROP 2 LAST PATH I173
J 0
(-6925 2425);
DISPLAY 1.021277 (-6925 2425);
PAINT ORANGE (-6925 2425);
DISPLAY INVISIBLE (-6925 2425);
FORCEADD OFFPAGE..1
R 2
(-1100 3150);
FORCEPROP 2 LAST $XR2 158 
J 0
(-674 3150);
DISPLAY 0.638298 (-674 3150);
PAINT MONO (-674 3150);
FORCEPROP 2 LAST $XR1 144 
J 0
(-794 3150);
DISPLAY 0.638298 (-794 3150);
PAINT MONO (-794 3150);
FORCEPROP 2 LAST $XR0 190 
J 0
(-914 3150);
DISPLAY 0.638298 (-914 3150);
PAINT MONO (-914 3150);
FORCEPROP 2 LAST CDS_LIB mstr_standard
J 0
(-1100 3150);
PAINT MONO (-1100 3150);
DISPLAY INVISIBLE (-1100 3150);
FORCEPROP 1 LAST OFFPAGE TRUE
J 2
(-1425 3025);
PAINT GREEN (-1425 3025);
DISPLAY INVISIBLE (-1425 3025);
FORCEPROP 1 LAST COMMENT_BODY TRUE
J 2
(-1225 3050);
DISPLAY 1.404255 (-1225 3050);
PAINT PEACH (-1225 3050);
DISPLAY INVISIBLE (-1225 3050);
FORCEPROP 2 LAST PATH I182
J 0
(-925 3225);
DISPLAY 1.021277 (-925 3225);
PAINT ORANGE (-925 3225);
DISPLAY INVISIBLE (-925 3225);
FORCEADD OFFPAGE..1
R 2
(-1100 4250);
FORCEPROP 2 LAST $XR1 144 
J 0
(-794 4250);
DISPLAY 0.638298 (-794 4250);
PAINT MONO (-794 4250);
FORCEPROP 2 LAST $XR0 134 
J 0
(-914 4250);
DISPLAY 0.638298 (-914 4250);
PAINT MONO (-914 4250);
FORCEPROP 2 LAST CDS_LIB mstr_standard
J 0
(-1100 4250);
PAINT MONO (-1100 4250);
DISPLAY INVISIBLE (-1100 4250);
FORCEPROP 1 LAST OFFPAGE TRUE
J 2
(-1425 4125);
PAINT GREEN (-1425 4125);
DISPLAY INVISIBLE (-1425 4125);
FORCEPROP 1 LAST COMMENT_BODY TRUE
J 2
(-1225 4150);
DISPLAY 1.404255 (-1225 4150);
PAINT PEACH (-1225 4150);
DISPLAY INVISIBLE (-1225 4150);
FORCEPROP 2 LAST PATH I183
J 0
(-925 4325);
DISPLAY 1.021277 (-925 4325);
PAINT ORANGE (-925 4325);
DISPLAY INVISIBLE (-925 4325);
FORCEADD OFFPAGE..4
(-300 2700);
FORCEPROP 2 LAST $XR1 145 
J 0
(-114 2664);
DISPLAY 0.638298 (-114 2664);
PAINT MONO (-114 2664);
FORCEPROP 2 LAST $XR0 89 
J 0
(-114 2700);
DISPLAY 0.638298 (-114 2700);
PAINT MONO (-114 2700);
FORCEPROP 2 LAST PATH I184
J 0
(-125 2775);
DISPLAY 1.021277 (-125 2775);
PAINT ORANGE (-125 2775);
DISPLAY INVISIBLE (-125 2775);
FORCEPROP 1 LAST COMMENT_BODY TRUE
J 0
(-325 2600);
DISPLAY 0.872340 (-325 2600);
PAINT GREEN (-325 2600);
DISPLAY INVISIBLE (-325 2600);
FORCEPROP 1 LAST OFFPAGE TRUE
J 0
(25 2575);
DISPLAY 0.872340 (25 2575);
PAINT GREEN (25 2575);
DISPLAY INVISIBLE (25 2575);
FORCEPROP 2 LAST CDS_LIB mstr_standard
J 0
(-300 2700);
PAINT MONO (-300 2700);
DISPLAY INVISIBLE (-300 2700);
FORCEADD OFFPAGE..2
(-1325 2750);
FORCEPROP 2 LAST CDS_LIB mstr_standard
J 0
(-1325 2750);
PAINT MONO (-1325 2750);
DISPLAY INVISIBLE (-1325 2750);
FORCEPROP 1 LAST OFFPAGE TRUE
J 0
(-1000 2625);
DISPLAY 0.872340 (-1000 2625);
PAINT GREEN (-1000 2625);
DISPLAY INVISIBLE (-1000 2625);
FORCEPROP 1 LAST COMMENT_BODY TRUE
J 0
(-1370 2655);
DISPLAY 0.872340 (-1370 2655);
PAINT GREEN (-1370 2655);
DISPLAY INVISIBLE (-1370 2655);
FORCEPROP 2 LAST PATH I185
J 0
(-1150 2825);
DISPLAY 1.021277 (-1150 2825);
PAINT ORANGE (-1150 2825);
DISPLAY INVISIBLE (-1150 2825);
FORCEPROP 2 LAST $XR2 182 
J 0
(-1136 2750);
DISPLAY 0.638298 (-1136 2750);
PAINT MONO (-1136 2750);
DISPLAY INVISIBLE (-1136 2750);
FORCEPROP 2 LAST $XR1 145 
J 0
(-1136 2750);
DISPLAY 0.638298 (-1136 2750);
PAINT MONO (-1136 2750);
DISPLAY INVISIBLE (-1136 2750);
FORCEPROP 2 LAST $XR0 133 
J 0
(-1136 2750);
DISPLAY 0.638298 (-1136 2750);
PAINT MONO (-1136 2750);
DISPLAY INVISIBLE (-1136 2750);
FORCEADD OFFPAGE..1
R 2
(-1325 3000);
FORCEPROP 2 LAST $XR0 145 
J 0
(-1139 3000);
DISPLAY 0.638298 (-1139 3000);
PAINT MONO (-1139 3000);
FORCEPROP 2 LAST CDS_LIB mstr_standard
J 0
(-1325 3000);
PAINT MONO (-1325 3000);
DISPLAY INVISIBLE (-1325 3000);
FORCEPROP 1 LAST OFFPAGE TRUE
J 2
(-1650 2875);
PAINT GREEN (-1650 2875);
DISPLAY INVISIBLE (-1650 2875);
FORCEPROP 1 LAST COMMENT_BODY TRUE
J 2
(-1450 2900);
DISPLAY 1.404255 (-1450 2900);
PAINT PEACH (-1450 2900);
DISPLAY INVISIBLE (-1450 2900);
FORCEPROP 2 LAST PATH I187
J 0
(-1150 3075);
DISPLAY 1.021277 (-1150 3075);
PAINT ORANGE (-1150 3075);
DISPLAY INVISIBLE (-1150 3075);
FORCEADD OFFPAGE..1
(-6275 3250);
FORCEPROP 2 LAST $XR1 190 
J 0
(-6677 3250);
DISPLAY 0.638298 (-6677 3250);
PAINT MONO (-6677 3250);
FORCEPROP 2 LAST $XR0 135 
J 0
(-6557 3250);
DISPLAY 0.638298 (-6557 3250);
PAINT MONO (-6557 3250);
FORCEPROP 2 LAST PATH I195
J 0
(-6225 3325);
DISPLAY 1.021277 (-6225 3325);
PAINT ORANGE (-6225 3325);
DISPLAY INVISIBLE (-6225 3325);
FORCEPROP 1 LAST COMMENT_BODY TRUE
J 0
(-6150 3150);
DISPLAY 1.404255 (-6150 3150);
PAINT PEACH (-6150 3150);
DISPLAY INVISIBLE (-6150 3150);
FORCEPROP 1 LAST OFFPAGE TRUE
J 0
(-5950 3125);
PAINT GREEN (-5950 3125);
DISPLAY INVISIBLE (-5950 3125);
FORCEPROP 2 LAST CDS_LIB mstr_standard
J 0
(-6275 3250);
PAINT MONO (-6275 3250);
DISPLAY INVISIBLE (-6275 3250);
FORCEADD OFFPAGE..5
(-6275 2800);
FORCEPROP 2 LAST $XR0 189 
J 0
(-6530 2800);
DISPLAY 0.638298 (-6530 2800);
PAINT MONO (-6530 2800);
FORCEPROP 2 LAST PATH I196
J 0
(-6225 2875);
DISPLAY 1.021277 (-6225 2875);
PAINT ORANGE (-6225 2875);
DISPLAY INVISIBLE (-6225 2875);
FORCEPROP 1 LAST COMMENT_BODY TRUE
J 0
(-6175 2725);
DISPLAY 0.872340 (-6175 2725);
PAINT GREEN (-6175 2725);
DISPLAY INVISIBLE (-6175 2725);
FORCEPROP 1 LAST OFFPAGE TRUE
J 0
(-5950 2675);
DISPLAY 0.872340 (-5950 2675);
PAINT GREEN (-5950 2675);
DISPLAY INVISIBLE (-5950 2675);
FORCEPROP 2 LAST CDS_LIB mstr_standard
J 0
(-6275 2800);
PAINT MONO (-6275 2800);
DISPLAY INVISIBLE (-6275 2800);
FORCEADD OFFPAGE..5
(-6275 2850);
FORCEPROP 2 LAST PATH I197
J 0
(-6225 2925);
DISPLAY 1.021277 (-6225 2925);
PAINT ORANGE (-6225 2925);
DISPLAY INVISIBLE (-6225 2925);
FORCEPROP 1 LAST COMMENT_BODY TRUE
J 0
(-6175 2775);
DISPLAY 1.404255 (-6175 2775);
PAINT PEACH (-6175 2775);
DISPLAY INVISIBLE (-6175 2775);
FORCEPROP 1 LAST OFFPAGE TRUE
J 0
(-5950 2725);
PAINT GREEN (-5950 2725);
DISPLAY INVISIBLE (-5950 2725);
FORCEPROP 2 LAST CDS_LIB mstr_standard
J 0
(-6275 2850);
PAINT MONO (-6275 2850);
DISPLAY INVISIBLE (-6275 2850);
FORCEPROP 2 LAST $XR0 189 
J 0
(-6704 2850);
DISPLAY 0.638298 (-6704 2850);
PAINT MONO (-6704 2850);
DISPLAY INVISIBLE (-6704 2850);
FORCEADD OFFPAGE..5
(-6275 2750);
FORCEPROP 2 LAST $XR0 189 
J 0
(-6530 2750);
DISPLAY 0.638298 (-6530 2750);
PAINT MONO (-6530 2750);
FORCEPROP 2 LAST PATH I198
J 0
(-6225 2825);
DISPLAY 1.021277 (-6225 2825);
PAINT ORANGE (-6225 2825);
DISPLAY INVISIBLE (-6225 2825);
FORCEPROP 1 LAST COMMENT_BODY TRUE
J 0
(-6175 2675);
DISPLAY 1.404255 (-6175 2675);
PAINT PEACH (-6175 2675);
DISPLAY INVISIBLE (-6175 2675);
FORCEPROP 1 LAST OFFPAGE TRUE
J 0
(-5950 2625);
PAINT GREEN (-5950 2625);
DISPLAY INVISIBLE (-5950 2625);
FORCEPROP 2 LAST CDS_LIB mstr_standard
J 0
(-6275 2750);
PAINT MONO (-6275 2750);
DISPLAY INVISIBLE (-6275 2750);
FORCEADD OFFPAGE..1
(-6275 2900);
FORCEPROP 2 LAST $XR0 189 
J 0
(-6557 2900);
DISPLAY 0.638298 (-6557 2900);
PAINT MONO (-6557 2900);
FORCEPROP 2 LAST PATH I199
J 0
(-6225 2975);
DISPLAY 1.021277 (-6225 2975);
PAINT ORANGE (-6225 2975);
DISPLAY INVISIBLE (-6225 2975);
FORCEPROP 1 LAST COMMENT_BODY TRUE
J 0
(-6150 2800);
DISPLAY 0.872340 (-6150 2800);
PAINT GREEN (-6150 2800);
DISPLAY INVISIBLE (-6150 2800);
FORCEPROP 1 LAST OFFPAGE TRUE
J 0
(-5950 2775);
DISPLAY 0.872340 (-5950 2775);
PAINT GREEN (-5950 2775);
DISPLAY INVISIBLE (-5950 2775);
FORCEPROP 2 LAST CDS_LIB mstr_standard
J 0
(-6275 2900);
PAINT MONO (-6275 2900);
DISPLAY INVISIBLE (-6275 2900);
FORCEADD OFFPAGE..1
(-6275 2700);
FORCEPROP 2 LAST PATH I200
J 0
(-6225 2775);
DISPLAY 1.021277 (-6225 2775);
PAINT ORANGE (-6225 2775);
DISPLAY INVISIBLE (-6225 2775);
FORCEPROP 1 LAST COMMENT_BODY TRUE
J 0
(-6150 2600);
DISPLAY 1.404255 (-6150 2600);
PAINT PEACH (-6150 2600);
DISPLAY INVISIBLE (-6150 2600);
FORCEPROP 1 LAST OFFPAGE TRUE
J 0
(-5950 2575);
PAINT GREEN (-5950 2575);
DISPLAY INVISIBLE (-5950 2575);
FORCEPROP 2 LAST CDS_LIB mstr_standard
J 0
(-6275 2700);
PAINT MONO (-6275 2700);
DISPLAY INVISIBLE (-6275 2700);
FORCEPROP 2 LAST $XR0 136 
J 0
(-6701 2700);
DISPLAY 0.638298 (-6701 2700);
PAINT MONO (-6701 2700);
DISPLAY INVISIBLE (-6701 2700);
FORCEADD OFFPAGE..5
R 2
(-1100 4100);
FORCEPROP 2 LAST $XR2 175 
J 0
(-671 4100);
DISPLAY 0.638298 (-671 4100);
PAINT MONO (-671 4100);
FORCEPROP 2 LAST $XR1 146 
J 0
(-791 4100);
DISPLAY 0.638298 (-791 4100);
PAINT MONO (-791 4100);
FORCEPROP 2 LAST $XR0 133 
J 0
(-911 4100);
DISPLAY 0.638298 (-911 4100);
PAINT MONO (-911 4100);
FORCEPROP 2 LAST PATH I201
J 0
(-925 4175);
DISPLAY 1.021277 (-925 4175);
PAINT ORANGE (-925 4175);
DISPLAY INVISIBLE (-925 4175);
FORCEPROP 1 LAST COMMENT_BODY TRUE
J 2
(-1200 4025);
DISPLAY 0.872340 (-1200 4025);
PAINT GREEN (-1200 4025);
DISPLAY INVISIBLE (-1200 4025);
FORCEPROP 1 LAST OFFPAGE TRUE
J 2
(-1425 3975);
DISPLAY 0.872340 (-1425 3975);
PAINT GREEN (-1425 3975);
DISPLAY INVISIBLE (-1425 3975);
FORCEPROP 2 LAST CDS_LIB mstr_standard
J 0
(-1100 4100);
PAINT MONO (-1100 4100);
DISPLAY INVISIBLE (-1100 4100);
FORCEADD OFFPAGE..5
(-6275 3200);
FORCEPROP 2 LAST $XR1 191 
J 0
(-6650 3200);
DISPLAY 0.638298 (-6650 3200);
PAINT MONO (-6650 3200);
FORCEPROP 2 LAST $XR0 144 
J 0
(-6530 3200);
DISPLAY 0.638298 (-6530 3200);
PAINT MONO (-6530 3200);
FORCEPROP 2 LAST PATH I202
J 0
(-6225 3275);
DISPLAY 1.021277 (-6225 3275);
PAINT ORANGE (-6225 3275);
DISPLAY INVISIBLE (-6225 3275);
FORCEPROP 1 LAST COMMENT_BODY TRUE
J 0
(-6175 3125);
DISPLAY 1.404255 (-6175 3125);
PAINT PEACH (-6175 3125);
DISPLAY INVISIBLE (-6175 3125);
FORCEPROP 1 LAST OFFPAGE TRUE
J 0
(-5950 3075);
PAINT GREEN (-5950 3075);
DISPLAY INVISIBLE (-5950 3075);
FORCEPROP 2 LAST CDS_LIB mstr_standard
J 0
(-6275 3200);
PAINT MONO (-6275 3200);
DISPLAY INVISIBLE (-6275 3200);
FORCEADD OFFPAGE..5
(-6275 3500);
FORCEPROP 2 LAST $XR2 145 
J 0
(-6770 3500);
DISPLAY 0.638298 (-6770 3500);
PAINT MONO (-6770 3500);
FORCEPROP 2 LAST $XR1 119 
J 0
(-6650 3500);
DISPLAY 0.638298 (-6650 3500);
PAINT MONO (-6650 3500);
FORCEPROP 2 LAST $XR0 133 
J 0
(-6530 3500);
DISPLAY 0.638298 (-6530 3500);
PAINT MONO (-6530 3500);
FORCEPROP 2 LAST PATH I208
J 0
(-6225 3575);
DISPLAY 1.021277 (-6225 3575);
PAINT ORANGE (-6225 3575);
DISPLAY INVISIBLE (-6225 3575);
FORCEPROP 1 LAST COMMENT_BODY TRUE
J 0
(-6175 3425);
DISPLAY 0.872340 (-6175 3425);
PAINT GREEN (-6175 3425);
DISPLAY INVISIBLE (-6175 3425);
FORCEPROP 1 LAST OFFPAGE TRUE
J 0
(-5950 3375);
DISPLAY 0.872340 (-5950 3375);
PAINT GREEN (-5950 3375);
DISPLAY INVISIBLE (-5950 3375);
FORCEPROP 2 LAST CDS_LIB mstr_standard
J 0
(-6275 3500);
PAINT MONO (-6275 3500);
DISPLAY INVISIBLE (-6275 3500);
FORCEADD OFFPAGE..5
(-6275 3000);
FORCEPROP 2 LAST $XR0 178 
J 0
(-6530 3000);
DISPLAY 0.638298 (-6530 3000);
PAINT MONO (-6530 3000);
FORCEPROP 2 LAST PATH I210
J 0
(-6225 3075);
DISPLAY 1.021277 (-6225 3075);
PAINT ORANGE (-6225 3075);
DISPLAY INVISIBLE (-6225 3075);
FORCEPROP 1 LAST COMMENT_BODY TRUE
J 0
(-6175 2925);
DISPLAY 1.404255 (-6175 2925);
PAINT PEACH (-6175 2925);
DISPLAY INVISIBLE (-6175 2925);
FORCEPROP 1 LAST OFFPAGE TRUE
J 0
(-5950 2875);
PAINT GREEN (-5950 2875);
DISPLAY INVISIBLE (-5950 2875);
FORCEPROP 2 LAST CDS_LIB mstr_standard
J 0
(-6275 3000);
PAINT MONO (-6275 3000);
DISPLAY INVISIBLE (-6275 3000);
FORCEADD OFFPAGE..5
(-6275 2950);
FORCEPROP 2 LAST $XR0 178 
J 0
(-6530 2950);
DISPLAY 0.638298 (-6530 2950);
PAINT MONO (-6530 2950);
FORCEPROP 2 LAST PATH I211
J 0
(-6225 3025);
DISPLAY 1.021277 (-6225 3025);
PAINT ORANGE (-6225 3025);
DISPLAY INVISIBLE (-6225 3025);
FORCEPROP 1 LAST COMMENT_BODY TRUE
J 0
(-6175 2875);
DISPLAY 1.404255 (-6175 2875);
PAINT PEACH (-6175 2875);
DISPLAY INVISIBLE (-6175 2875);
FORCEPROP 1 LAST OFFPAGE TRUE
J 0
(-5950 2825);
PAINT GREEN (-5950 2825);
DISPLAY INVISIBLE (-5950 2825);
FORCEPROP 2 LAST CDS_LIB mstr_standard
J 0
(-6275 2950);
PAINT MONO (-6275 2950);
DISPLAY INVISIBLE (-6275 2950);
FORCEADD OFFPAGE..5
R 2
(-1100 4050);
FORCEPROP 2 LAST $XR2 200 
J 0
(-671 4050);
DISPLAY 0.638298 (-671 4050);
PAINT MONO (-671 4050);
FORCEPROP 2 LAST $XR1 145 
J 0
(-791 4050);
DISPLAY 0.638298 (-791 4050);
PAINT MONO (-791 4050);
FORCEPROP 2 LAST $XR0 126 
J 0
(-911 4050);
DISPLAY 0.638298 (-911 4050);
PAINT MONO (-911 4050);
FORCEPROP 2 LAST PATH I212
J 0
(-925 4125);
DISPLAY 1.021277 (-925 4125);
PAINT ORANGE (-925 4125);
DISPLAY INVISIBLE (-925 4125);
FORCEPROP 1 LAST COMMENT_BODY TRUE
J 2
(-1200 3975);
DISPLAY 0.872340 (-1200 3975);
PAINT GREEN (-1200 3975);
DISPLAY INVISIBLE (-1200 3975);
FORCEPROP 1 LAST OFFPAGE TRUE
J 2
(-1425 3925);
DISPLAY 0.872340 (-1425 3925);
PAINT GREEN (-1425 3925);
DISPLAY INVISIBLE (-1425 3925);
FORCEPROP 2 LAST CDS_LIB mstr_standard
J 0
(-1100 4050);
PAINT MONO (-1100 4050);
DISPLAY INVISIBLE (-1100 4050);
FORCEADD OFFPAGE..5
(-6275 3600);
FORCEPROP 2 LAST PATH I213
J 0
(-6225 3675);
DISPLAY 1.021277 (-6225 3675);
PAINT ORANGE (-6225 3675);
DISPLAY INVISIBLE (-6225 3675);
FORCEPROP 1 LAST COMMENT_BODY TRUE
J 0
(-6175 3525);
DISPLAY 1.404255 (-6175 3525);
PAINT PEACH (-6175 3525);
DISPLAY INVISIBLE (-6175 3525);
FORCEPROP 1 LAST OFFPAGE TRUE
J 0
(-5950 3475);
PAINT GREEN (-5950 3475);
DISPLAY INVISIBLE (-5950 3475);
FORCEPROP 2 LAST CDS_LIB mstr_standard
J 0
(-6275 3600);
PAINT MONO (-6275 3600);
DISPLAY INVISIBLE (-6275 3600);
FORCEPROP 2 LAST $XR0 178 
J 0
(-6704 3600);
DISPLAY 0.638298 (-6704 3600);
PAINT MONO (-6704 3600);
DISPLAY INVISIBLE (-6704 3600);
FORCEADD OFFPAGE..5
(-6275 3550);
FORCEPROP 2 LAST PATH I215
J 0
(-6225 3625);
DISPLAY 1.021277 (-6225 3625);
PAINT ORANGE (-6225 3625);
DISPLAY INVISIBLE (-6225 3625);
FORCEPROP 1 LAST COMMENT_BODY TRUE
J 0
(-6175 3475);
DISPLAY 1.404255 (-6175 3475);
PAINT PEACH (-6175 3475);
DISPLAY INVISIBLE (-6175 3475);
FORCEPROP 1 LAST OFFPAGE TRUE
J 0
(-5950 3425);
PAINT GREEN (-5950 3425);
DISPLAY INVISIBLE (-5950 3425);
FORCEPROP 2 LAST CDS_LIB mstr_standard
J 0
(-6275 3550);
PAINT MONO (-6275 3550);
DISPLAY INVISIBLE (-6275 3550);
FORCEPROP 2 LAST $XR0 178 
J 0
(-6704 3550);
DISPLAY 0.638298 (-6704 3550);
PAINT MONO (-6704 3550);
DISPLAY INVISIBLE (-6704 3550);
FORCEADD OFFPAGE..5
(-6275 3100);
FORCEPROP 2 LAST PATH I217
J 0
(-6525 3150);
DISPLAY 1.021277 (-6525 3150);
PAINT ORANGE (-6525 3150);
DISPLAY INVISIBLE (-6525 3150);
FORCEPROP 1 LAST COMMENT_BODY TRUE
J 0
(-6175 3025);
DISPLAY 1.404255 (-6175 3025);
PAINT PEACH (-6175 3025);
DISPLAY INVISIBLE (-6175 3025);
FORCEPROP 1 LAST OFFPAGE TRUE
J 0
(-5950 2975);
PAINT GREEN (-5950 2975);
DISPLAY INVISIBLE (-5950 2975);
FORCEPROP 2 LAST CDS_LIB mstr_standard
J 0
(-6275 3100);
PAINT MONO (-6275 3100);
DISPLAY INVISIBLE (-6275 3100);
FORCEPROP 2 LAST $XR0 178 
J 0
(-6704 3100);
DISPLAY 0.638298 (-6704 3100);
PAINT MONO (-6704 3100);
DISPLAY INVISIBLE (-6704 3100);
FORCEADD RES..1
(-6650 3850);
FORCEPROP 1 LAST LOCATION R2M1
J 0
(-6700 3950);
DISPLAY 0.617021 (-6700 3950);
PAINT AQUA (-6700 3950);
FORCEPROP 1 LASTPIN (-6550 3850) $PN 2
J 0
(-6588 3862);
DISPLAY 0.617021 (-6588 3862);
PAINT ORANGE (-6588 3862);
FORCEPROP 1 LAST TOLERANCE 1%
J 0
(-6800 3900);
DISPLAY 0.617021 (-6800 3900);
PAINT SKYBLUE (-6800 3900);
FORCEPROP 1 LAST VALUE 33.2
J 2
(-6750 3950);
DISPLAY 0.617021 (-6750 3950);
PAINT SKYBLUE (-6750 3950);
FORCEPROP 1 LASTPIN (-6750 3850) $PN 1
J 0
(-6738 3862);
DISPLAY 0.617021 (-6738 3862);
PAINT ORANGE (-6738 3862);
FORCEPROP 1 LAST MATERIAL CHIP
J 0
(-6700 3900);
DISPLAY 0.617021 (-6700 3900);
PAINT SKYBLUE (-6700 3900);
FORCEPROP 1 LAST WATTAGE 1/16W
J 2
(-6325 3900);
DISPLAY 0.617021 (-6325 3900);
PAINT SKYBLUE (-6325 3900);
FORCEPROP 1 LAST PACK_TYPE 0402
J 0
(-6575 3900);
DISPLAY 0.617021 (-6575 3900);
PAINT SKYBLUE (-6575 3900);
FORCEPROP 1 LAST PART_NUMBER G21796-074
J 0
(-6300 3900);
DISPLAY 0.617021 (-6300 3900);
PAINT BLUE (-6300 3900);
FORCEPROP 2 LAST ROOM CPLD
J 0
(-6700 3990);
DISPLAY 0.787234 (-6700 3990);
PAINT SKYBLUE (-6700 3990);
DISPLAY INVISIBLE (-6700 3990);
FORCEPROP 2 LAST CDS_LOCATION R2M1
J 0
(-6675 3875);
DISPLAY 0.617021 (-6675 3875);
PAINT AQUA (-6675 3875);
DISPLAY INVISIBLE (-6675 3875);
FORCEPROP 2 LAST SEC 1
J 0
(-6700 4050);
DISPLAY 0.680851 (-6700 4050);
PAINT MONO (-6700 4050);
DISPLAY INVISIBLE (-6700 4050);
FORCEPROP 2 LAST SEC_TYPE 0402
J 0
(-6700 4050);
DISPLAY 1.021277 (-6700 4050);
PAINT ORANGE (-6700 4050);
DISPLAY INVISIBLE (-6700 4050);
FORCEPROP 2 LAST CDS_LIB mstr_discrete
J 0
(-6650 3850);
PAINT MONO (-6650 3850);
DISPLAY INVISIBLE (-6650 3850);
FORCEPROP 1 LAST PATH I218
J 0
(-6700 4000);
DISPLAY 0.978723 (-6700 4000);
PAINT WHITE (-6700 4000);
DISPLAY INVISIBLE (-6700 4000);
FORCEADD RES..1
(-6100 2050);
FORCEPROP 1 LAST MATERIAL CHIP
J 0
(-6150 2000);
DISPLAY 0.617021 (-6150 2000);
PAINT SKYBLUE (-6150 2000);
FORCEPROP 1 LAST VALUE 33.2
J 2
(-6250 2050);
DISPLAY 0.617021 (-6250 2050);
PAINT SKYBLUE (-6250 2050);
FORCEPROP 1 LAST PACK_TYPE 0402
J 0
(-6025 2000);
DISPLAY 0.617021 (-6025 2000);
PAINT SKYBLUE (-6025 2000);
FORCEPROP 1 LAST TOLERANCE 1%
J 0
(-6250 2000);
DISPLAY 0.617021 (-6250 2000);
PAINT SKYBLUE (-6250 2000);
FORCEPROP 1 LASTPIN (-6200 2050) $PN 1
J 0
(-6188 2062);
DISPLAY 0.617021 (-6188 2062);
PAINT ORANGE (-6188 2062);
FORCEPROP 1 LAST LOCATION R2N26
J 0
(-6175 2125);
DISPLAY 0.617021 (-6175 2125);
PAINT AQUA (-6175 2125);
FORCEPROP 1 LAST WATTAGE 1/16W
J 2
(-6275 2000);
DISPLAY 0.617021 (-6275 2000);
PAINT SKYBLUE (-6275 2000);
FORCEPROP 1 LASTPIN (-6000 2050) $PN 2
J 0
(-6038 2062);
DISPLAY 0.617021 (-6038 2062);
PAINT ORANGE (-6038 2062);
FORCEPROP 1 LAST PART_NUMBER G21796-074
J 0
(-5925 2000);
DISPLAY 0.617021 (-5925 2000);
PAINT BLUE (-5925 2000);
FORCEPROP 1 LAST PATH I219
J 0
(-6150 2200);
DISPLAY 0.978723 (-6150 2200);
PAINT WHITE (-6150 2200);
DISPLAY INVISIBLE (-6150 2200);
FORCEPROP 2 LAST CDS_LIB mstr_discrete
J 0
(-6100 2050);
PAINT MONO (-6100 2050);
DISPLAY INVISIBLE (-6100 2050);
FORCEPROP 2 LAST SEC_TYPE 0402
J 0
(-6150 2250);
DISPLAY 1.021277 (-6150 2250);
PAINT ORANGE (-6150 2250);
DISPLAY INVISIBLE (-6150 2250);
FORCEPROP 2 LAST SEC 1
J 0
(-6150 2250);
DISPLAY 0.680851 (-6150 2250);
PAINT MONO (-6150 2250);
DISPLAY INVISIBLE (-6150 2250);
FORCEPROP 2 LAST CDS_LOCATION R2N26
J 0
(-6125 2075);
DISPLAY 0.617021 (-6125 2075);
PAINT AQUA (-6125 2075);
DISPLAY INVISIBLE (-6125 2075);
FORCEPROP 2 LAST ROOM CPLD
J 0
(-6150 2190);
DISPLAY 0.787234 (-6150 2190);
PAINT SKYBLUE (-6150 2190);
DISPLAY INVISIBLE (-6150 2190);
FORCEADD OFFPAGE..2
(-1325 1250);
FORCEPROP 2 LAST $XR0 188 
J 0
(-1136 1250);
DISPLAY 0.638298 (-1136 1250);
PAINT MONO (-1136 1250);
FORCEPROP 2 LAST CDS_LIB mstr_standard
J 0
(-1325 1250);
PAINT ORANGE (-1325 1250);
DISPLAY INVISIBLE (-1325 1250);
FORCEPROP 1 LAST OFFPAGE TRUE
J 0
(-1000 1125);
DISPLAY 0.872340 (-1000 1125);
PAINT GREEN (-1000 1125);
DISPLAY INVISIBLE (-1000 1125);
FORCEPROP 1 LAST COMMENT_BODY TRUE
J 0
(-1370 1155);
DISPLAY 0.872340 (-1370 1155);
PAINT GREEN (-1370 1155);
DISPLAY INVISIBLE (-1370 1155);
FORCEPROP 2 LAST PATH I222
J 0
(-1150 1325);
DISPLAY 1.021277 (-1150 1325);
PAINT ORANGE (-1150 1325);
DISPLAY INVISIBLE (-1150 1325);
FORCEADD OFFPAGE..2
(-1325 1300);
FORCEPROP 2 LAST $XR0 188 
J 0
(-1136 1300);
DISPLAY 0.638298 (-1136 1300);
PAINT MONO (-1136 1300);
FORCEPROP 2 LAST CDS_LIB mstr_standard
J 0
(-1325 1300);
PAINT ORANGE (-1325 1300);
DISPLAY INVISIBLE (-1325 1300);
FORCEPROP 1 LAST OFFPAGE TRUE
J 0
(-1000 1175);
DISPLAY 0.872340 (-1000 1175);
PAINT GREEN (-1000 1175);
DISPLAY INVISIBLE (-1000 1175);
FORCEPROP 1 LAST COMMENT_BODY TRUE
J 0
(-1370 1205);
DISPLAY 0.872340 (-1370 1205);
PAINT GREEN (-1370 1205);
DISPLAY INVISIBLE (-1370 1205);
FORCEPROP 2 LAST PATH I223
J 0
(-1150 1375);
DISPLAY 1.021277 (-1150 1375);
PAINT ORANGE (-1150 1375);
DISPLAY INVISIBLE (-1150 1375);
FORCEADD OFFPAGE..2
(-1325 1350);
FORCEPROP 2 LAST $XR0 188 
J 0
(-1136 1350);
DISPLAY 0.638298 (-1136 1350);
PAINT MONO (-1136 1350);
FORCEPROP 2 LAST CDS_LIB mstr_standard
J 0
(-1325 1350);
PAINT ORANGE (-1325 1350);
DISPLAY INVISIBLE (-1325 1350);
FORCEPROP 1 LAST OFFPAGE TRUE
J 0
(-1000 1225);
DISPLAY 0.872340 (-1000 1225);
PAINT GREEN (-1000 1225);
DISPLAY INVISIBLE (-1000 1225);
FORCEPROP 1 LAST COMMENT_BODY TRUE
J 0
(-1370 1255);
DISPLAY 0.872340 (-1370 1255);
PAINT GREEN (-1370 1255);
DISPLAY INVISIBLE (-1370 1255);
FORCEPROP 2 LAST PATH I224
J 0
(-1150 1425);
DISPLAY 1.021277 (-1150 1425);
PAINT ORANGE (-1150 1425);
DISPLAY INVISIBLE (-1150 1425);
FORCEADD OFFPAGE..2
(-1325 1400);
FORCEPROP 2 LAST $XR0 188 
J 0
(-1136 1400);
DISPLAY 0.638298 (-1136 1400);
PAINT MONO (-1136 1400);
FORCEPROP 2 LAST CDS_LIB mstr_standard
J 0
(-1325 1400);
PAINT ORANGE (-1325 1400);
DISPLAY INVISIBLE (-1325 1400);
FORCEPROP 1 LAST OFFPAGE TRUE
J 0
(-1000 1275);
DISPLAY 0.872340 (-1000 1275);
PAINT GREEN (-1000 1275);
DISPLAY INVISIBLE (-1000 1275);
FORCEPROP 1 LAST COMMENT_BODY TRUE
J 0
(-1370 1305);
DISPLAY 0.872340 (-1370 1305);
PAINT GREEN (-1370 1305);
DISPLAY INVISIBLE (-1370 1305);
FORCEPROP 2 LAST PATH I225
J 0
(-1150 1475);
DISPLAY 1.021277 (-1150 1475);
PAINT ORANGE (-1150 1475);
DISPLAY INVISIBLE (-1150 1475);
FORCEADD OFFPAGE..2
(-1325 1600);
FORCEPROP 2 LAST $XR0 188 
J 0
(-1136 1600);
DISPLAY 0.638298 (-1136 1600);
PAINT MONO (-1136 1600);
FORCEPROP 2 LAST CDS_LIB mstr_standard
J 0
(-1325 1600);
PAINT ORANGE (-1325 1600);
DISPLAY INVISIBLE (-1325 1600);
FORCEPROP 1 LAST OFFPAGE TRUE
J 0
(-1000 1475);
DISPLAY 0.872340 (-1000 1475);
PAINT GREEN (-1000 1475);
DISPLAY INVISIBLE (-1000 1475);
FORCEPROP 1 LAST COMMENT_BODY TRUE
J 0
(-1370 1505);
DISPLAY 0.872340 (-1370 1505);
PAINT GREEN (-1370 1505);
DISPLAY INVISIBLE (-1370 1505);
FORCEPROP 2 LAST PATH I226
J 0
(-1150 1675);
DISPLAY 1.021277 (-1150 1675);
PAINT ORANGE (-1150 1675);
DISPLAY INVISIBLE (-1150 1675);
FORCEADD OFFPAGE..2
(-1325 1650);
FORCEPROP 2 LAST $XR0 188 
J 0
(-1136 1650);
DISPLAY 0.638298 (-1136 1650);
PAINT MONO (-1136 1650);
FORCEPROP 2 LAST CDS_LIB mstr_standard
J 0
(-1325 1650);
PAINT ORANGE (-1325 1650);
DISPLAY INVISIBLE (-1325 1650);
FORCEPROP 1 LAST OFFPAGE TRUE
J 0
(-1000 1525);
DISPLAY 0.872340 (-1000 1525);
PAINT GREEN (-1000 1525);
DISPLAY INVISIBLE (-1000 1525);
FORCEPROP 1 LAST COMMENT_BODY TRUE
J 0
(-1370 1555);
DISPLAY 0.872340 (-1370 1555);
PAINT GREEN (-1370 1555);
DISPLAY INVISIBLE (-1370 1555);
FORCEPROP 2 LAST PATH I227
J 0
(-1150 1725);
DISPLAY 1.021277 (-1150 1725);
PAINT ORANGE (-1150 1725);
DISPLAY INVISIBLE (-1150 1725);
FORCEADD OFFPAGE..2
(-1325 1750);
FORCEPROP 2 LAST $XR0 188 
J 0
(-1136 1750);
DISPLAY 0.638298 (-1136 1750);
PAINT MONO (-1136 1750);
FORCEPROP 2 LAST CDS_LIB mstr_standard
J 0
(-1325 1750);
PAINT ORANGE (-1325 1750);
DISPLAY INVISIBLE (-1325 1750);
FORCEPROP 1 LAST OFFPAGE TRUE
J 0
(-1000 1625);
DISPLAY 0.872340 (-1000 1625);
PAINT GREEN (-1000 1625);
DISPLAY INVISIBLE (-1000 1625);
FORCEPROP 1 LAST COMMENT_BODY TRUE
J 0
(-1370 1655);
DISPLAY 0.872340 (-1370 1655);
PAINT GREEN (-1370 1655);
DISPLAY INVISIBLE (-1370 1655);
FORCEPROP 2 LAST PATH I228
J 0
(-1150 1825);
DISPLAY 1.021277 (-1150 1825);
PAINT ORANGE (-1150 1825);
DISPLAY INVISIBLE (-1150 1825);
FORCEADD OFFPAGE..6
R 2
(-1350 1700);
FORCEPROP 2 LAST $XR0 188 
J 0
(-1136 1700);
DISPLAY 0.638298 (-1136 1700);
PAINT MONO (-1136 1700);
FORCEPROP 2 LAST CDS_LIB mstr_standard
J 0
(-1350 1700);
PAINT ORANGE (-1350 1700);
DISPLAY INVISIBLE (-1350 1700);
FORCEPROP 1 LAST OFFPAGE TRUE
J 2
(-1675 1575);
PAINT GREEN (-1675 1575);
DISPLAY INVISIBLE (-1675 1575);
FORCEPROP 1 LAST COMMENT_BODY TRUE
J 2
(-1450 1625);
DISPLAY 1.404255 (-1450 1625);
PAINT PEACH (-1450 1625);
DISPLAY INVISIBLE (-1450 1625);
FORCEPROP 2 LAST PATH I233
J 0
(-1150 1775);
DISPLAY 1.021277 (-1150 1775);
PAINT ORANGE (-1150 1775);
DISPLAY INVISIBLE (-1150 1775);
FORCEADD OFFPAGE..6
R 2
(-1350 1800);
FORCEPROP 2 LAST $XR0 188 
J 0
(-1136 1800);
DISPLAY 0.638298 (-1136 1800);
PAINT MONO (-1136 1800);
FORCEPROP 2 LAST CDS_LIB mstr_standard
J 0
(-1350 1800);
PAINT ORANGE (-1350 1800);
DISPLAY INVISIBLE (-1350 1800);
FORCEPROP 1 LAST OFFPAGE TRUE
J 2
(-1675 1675);
PAINT GREEN (-1675 1675);
DISPLAY INVISIBLE (-1675 1675);
FORCEPROP 1 LAST COMMENT_BODY TRUE
J 2
(-1450 1725);
DISPLAY 1.404255 (-1450 1725);
PAINT PEACH (-1450 1725);
DISPLAY INVISIBLE (-1450 1725);
FORCEPROP 2 LAST PATH I234
J 0
(-1150 1875);
DISPLAY 1.021277 (-1150 1875);
PAINT ORANGE (-1150 1875);
DISPLAY INVISIBLE (-1150 1875);
FORCEADD OFFPAGE..4
(-1300 2350);
FORCEPROP 2 LAST $XR0 188 
J 0
(-1114 2350);
DISPLAY 0.638298 (-1114 2350);
PAINT MONO (-1114 2350);
FORCEPROP 2 LAST CDS_LIB mstr_standard
J 0
(-1300 2350);
PAINT ORANGE (-1300 2350);
DISPLAY INVISIBLE (-1300 2350);
FORCEPROP 1 LAST OFFPAGE TRUE
J 0
(-975 2225);
DISPLAY 0.872340 (-975 2225);
PAINT GREEN (-975 2225);
DISPLAY INVISIBLE (-975 2225);
FORCEPROP 1 LAST COMMENT_BODY TRUE
J 0
(-1325 2250);
DISPLAY 0.872340 (-1325 2250);
PAINT PEACH (-1325 2250);
DISPLAY INVISIBLE (-1325 2250);
FORCEPROP 2 LAST PATH I235
J 0
(-1125 2425);
DISPLAY 1.021277 (-1125 2425);
PAINT ORANGE (-1125 2425);
DISPLAY INVISIBLE (-1125 2425);
FORCEADD OFFPAGE..4
(-1300 2250);
FORCEPROP 2 LAST $XR0 188 
J 0
(-1114 2250);
DISPLAY 0.638298 (-1114 2250);
PAINT MONO (-1114 2250);
FORCEPROP 2 LAST CDS_LIB mstr_standard
J 0
(-1300 2250);
PAINT ORANGE (-1300 2250);
DISPLAY INVISIBLE (-1300 2250);
FORCEPROP 1 LAST OFFPAGE TRUE
J 0
(-975 2125);
DISPLAY 0.872340 (-975 2125);
PAINT GREEN (-975 2125);
DISPLAY INVISIBLE (-975 2125);
FORCEPROP 1 LAST COMMENT_BODY TRUE
J 0
(-1325 2150);
DISPLAY 0.872340 (-1325 2150);
PAINT PEACH (-1325 2150);
DISPLAY INVISIBLE (-1325 2150);
FORCEPROP 2 LAST PATH I236
J 0
(-1125 2325);
DISPLAY 1.021277 (-1125 2325);
PAINT ORANGE (-1125 2325);
DISPLAY INVISIBLE (-1125 2325);
FORCEADD OFFPAGE..4
(-1300 2150);
FORCEPROP 2 LAST $XR0 188 
J 0
(-1114 2150);
DISPLAY 0.638298 (-1114 2150);
PAINT MONO (-1114 2150);
FORCEPROP 2 LAST CDS_LIB mstr_standard
J 0
(-1300 2150);
PAINT ORANGE (-1300 2150);
DISPLAY INVISIBLE (-1300 2150);
FORCEPROP 1 LAST OFFPAGE TRUE
J 0
(-975 2025);
DISPLAY 0.872340 (-975 2025);
PAINT GREEN (-975 2025);
DISPLAY INVISIBLE (-975 2025);
FORCEPROP 1 LAST COMMENT_BODY TRUE
J 0
(-1325 2050);
DISPLAY 0.872340 (-1325 2050);
PAINT PEACH (-1325 2050);
DISPLAY INVISIBLE (-1325 2050);
FORCEPROP 2 LAST PATH I237
J 0
(-1125 2225);
DISPLAY 1.021277 (-1125 2225);
PAINT ORANGE (-1125 2225);
DISPLAY INVISIBLE (-1125 2225);
FORCEADD OFFPAGE..4
(-1300 2050);
FORCEPROP 2 LAST $XR0 188 
J 0
(-1114 2050);
DISPLAY 0.638298 (-1114 2050);
PAINT MONO (-1114 2050);
FORCEPROP 2 LAST CDS_LIB mstr_standard
J 0
(-1300 2050);
PAINT ORANGE (-1300 2050);
DISPLAY INVISIBLE (-1300 2050);
FORCEPROP 1 LAST OFFPAGE TRUE
J 0
(-975 1925);
DISPLAY 0.872340 (-975 1925);
PAINT GREEN (-975 1925);
DISPLAY INVISIBLE (-975 1925);
FORCEPROP 1 LAST COMMENT_BODY TRUE
J 0
(-1325 1950);
DISPLAY 0.872340 (-1325 1950);
PAINT PEACH (-1325 1950);
DISPLAY INVISIBLE (-1325 1950);
FORCEPROP 2 LAST PATH I238
J 0
(-1125 2125);
DISPLAY 1.021277 (-1125 2125);
PAINT ORANGE (-1125 2125);
DISPLAY INVISIBLE (-1125 2125);
FORCEADD OFFPAGE..2
(-1325 1450);
FORCEPROP 2 LAST $XR0 188 
J 0
(-1136 1450);
DISPLAY 0.638298 (-1136 1450);
PAINT MONO (-1136 1450);
FORCEPROP 2 LAST CDS_LIB mstr_standard
J 0
(-1325 1450);
PAINT ORANGE (-1325 1450);
DISPLAY INVISIBLE (-1325 1450);
FORCEPROP 1 LAST OFFPAGE TRUE
J 0
(-1000 1325);
DISPLAY 0.872340 (-1000 1325);
PAINT GREEN (-1000 1325);
DISPLAY INVISIBLE (-1000 1325);
FORCEPROP 1 LAST COMMENT_BODY TRUE
J 0
(-1370 1355);
DISPLAY 0.872340 (-1370 1355);
PAINT GREEN (-1370 1355);
DISPLAY INVISIBLE (-1370 1355);
FORCEPROP 2 LAST PATH I246
J 0
(-1125 1500);
DISPLAY 1.021277 (-1125 1500);
PAINT ORANGE (-1125 1500);
DISPLAY INVISIBLE (-1125 1500);
FORCEADD OFFPAGE..2
(-1325 1500);
FORCEPROP 2 LAST $XR0 188 
J 0
(-1136 1500);
DISPLAY 0.638298 (-1136 1500);
PAINT MONO (-1136 1500);
FORCEPROP 2 LAST CDS_LIB mstr_standard
J 0
(-1325 1500);
PAINT ORANGE (-1325 1500);
DISPLAY INVISIBLE (-1325 1500);
FORCEPROP 1 LAST OFFPAGE TRUE
J 0
(-1000 1375);
DISPLAY 0.872340 (-1000 1375);
PAINT GREEN (-1000 1375);
DISPLAY INVISIBLE (-1000 1375);
FORCEPROP 1 LAST COMMENT_BODY TRUE
J 0
(-1370 1405);
DISPLAY 0.872340 (-1370 1405);
PAINT GREEN (-1370 1405);
DISPLAY INVISIBLE (-1370 1405);
FORCEPROP 2 LAST PATH I247
J 0
(-1125 1550);
DISPLAY 1.021277 (-1125 1550);
PAINT ORANGE (-1125 1550);
DISPLAY INVISIBLE (-1125 1550);
FORCEADD OFFPAGE..2
(-1325 1550);
FORCEPROP 2 LAST $XR0 188 
J 0
(-1136 1550);
DISPLAY 0.638298 (-1136 1550);
PAINT MONO (-1136 1550);
FORCEPROP 2 LAST CDS_LIB mstr_standard
J 0
(-1325 1550);
PAINT ORANGE (-1325 1550);
DISPLAY INVISIBLE (-1325 1550);
FORCEPROP 1 LAST OFFPAGE TRUE
J 0
(-1000 1425);
DISPLAY 0.872340 (-1000 1425);
PAINT GREEN (-1000 1425);
DISPLAY INVISIBLE (-1000 1425);
FORCEPROP 1 LAST COMMENT_BODY TRUE
J 0
(-1370 1455);
DISPLAY 0.872340 (-1370 1455);
PAINT GREEN (-1370 1455);
DISPLAY INVISIBLE (-1370 1455);
FORCEPROP 2 LAST PATH I248
J 0
(-1125 1600);
DISPLAY 1.021277 (-1125 1600);
PAINT ORANGE (-1125 1600);
DISPLAY INVISIBLE (-1125 1600);
FORCEADD OFFPAGE..2
(-1325 1850);
FORCEPROP 2 LAST $XR0 188 
J 0
(-1136 1850);
DISPLAY 0.638298 (-1136 1850);
PAINT MONO (-1136 1850);
FORCEPROP 2 LAST CDS_LIB mstr_standard
J 0
(-1325 1850);
PAINT ORANGE (-1325 1850);
DISPLAY INVISIBLE (-1325 1850);
FORCEPROP 1 LAST OFFPAGE TRUE
J 0
(-1000 1725);
DISPLAY 0.872340 (-1000 1725);
PAINT GREEN (-1000 1725);
DISPLAY INVISIBLE (-1000 1725);
FORCEPROP 1 LAST COMMENT_BODY TRUE
J 0
(-1370 1755);
DISPLAY 0.872340 (-1370 1755);
PAINT GREEN (-1370 1755);
DISPLAY INVISIBLE (-1370 1755);
FORCEPROP 2 LAST PATH I249
J 0
(-1125 1900);
DISPLAY 1.021277 (-1125 1900);
PAINT ORANGE (-1125 1900);
DISPLAY INVISIBLE (-1125 1900);
FORCEADD OFFPAGE..6
R 2
(-1350 1900);
FORCEPROP 2 LAST $XR0 188 
J 0
(-1136 1900);
DISPLAY 0.638298 (-1136 1900);
PAINT MONO (-1136 1900);
FORCEPROP 2 LAST CDS_LIB mstr_standard
J 0
(-1350 1900);
PAINT ORANGE (-1350 1900);
DISPLAY INVISIBLE (-1350 1900);
FORCEPROP 1 LAST OFFPAGE TRUE
J 2
(-1675 1775);
PAINT GREEN (-1675 1775);
DISPLAY INVISIBLE (-1675 1775);
FORCEPROP 1 LAST COMMENT_BODY TRUE
J 2
(-1450 1825);
DISPLAY 1.404255 (-1450 1825);
PAINT PEACH (-1450 1825);
DISPLAY INVISIBLE (-1450 1825);
FORCEPROP 2 LAST PATH I250
J 0
(-1125 1950);
DISPLAY 1.021277 (-1125 1950);
PAINT ORANGE (-1125 1950);
DISPLAY INVISIBLE (-1125 1950);
FORCEADD OFFPAGE..6
R 2
(-1350 2000);
FORCEPROP 2 LAST $XR0 188 
J 0
(-1136 2000);
DISPLAY 0.638298 (-1136 2000);
PAINT MONO (-1136 2000);
FORCEPROP 2 LAST CDS_LIB mstr_standard
J 0
(-1350 2000);
PAINT ORANGE (-1350 2000);
DISPLAY INVISIBLE (-1350 2000);
FORCEPROP 1 LAST OFFPAGE TRUE
J 2
(-1675 1875);
PAINT GREEN (-1675 1875);
DISPLAY INVISIBLE (-1675 1875);
FORCEPROP 1 LAST COMMENT_BODY TRUE
J 2
(-1450 1925);
DISPLAY 1.404255 (-1450 1925);
PAINT PEACH (-1450 1925);
DISPLAY INVISIBLE (-1450 1925);
FORCEPROP 2 LAST PATH I251
J 0
(-1125 2050);
DISPLAY 1.021277 (-1125 2050);
PAINT ORANGE (-1125 2050);
DISPLAY INVISIBLE (-1125 2050);
FORCEADD OFFPAGE..2
(-1325 1950);
FORCEPROP 2 LAST $XR0 188 
J 0
(-1136 1950);
DISPLAY 0.638298 (-1136 1950);
PAINT MONO (-1136 1950);
FORCEPROP 2 LAST CDS_LIB mstr_standard
J 0
(-1325 1950);
PAINT ORANGE (-1325 1950);
DISPLAY INVISIBLE (-1325 1950);
FORCEPROP 1 LAST OFFPAGE TRUE
J 0
(-1000 1825);
DISPLAY 0.872340 (-1000 1825);
PAINT GREEN (-1000 1825);
DISPLAY INVISIBLE (-1000 1825);
FORCEPROP 1 LAST COMMENT_BODY TRUE
J 0
(-1370 1855);
DISPLAY 0.872340 (-1370 1855);
PAINT GREEN (-1370 1855);
DISPLAY INVISIBLE (-1370 1855);
FORCEPROP 2 LAST PATH I252
J 0
(-1125 2000);
DISPLAY 1.021277 (-1125 2000);
PAINT ORANGE (-1125 2000);
DISPLAY INVISIBLE (-1125 2000);
FORCEADD OFFPAGE..1
R 2
(-1100 3750);
FORCEPROP 2 LAST $XR0 126 
J 0
(-914 3750);
DISPLAY 0.638298 (-914 3750);
PAINT MONO (-914 3750);
FORCEPROP 2 LAST PATH I259
J 0
(-925 3825);
DISPLAY 1.021277 (-925 3825);
PAINT ORANGE (-925 3825);
DISPLAY INVISIBLE (-925 3825);
FORCEPROP 1 LAST COMMENT_BODY TRUE
J 2
(-1225 3650);
DISPLAY 1.404255 (-1225 3650);
PAINT PEACH (-1225 3650);
DISPLAY INVISIBLE (-1225 3650);
FORCEPROP 1 LAST OFFPAGE TRUE
J 2
(-1425 3625);
PAINT GREEN (-1425 3625);
DISPLAY INVISIBLE (-1425 3625);
FORCEPROP 2 LAST CDS_LIB mstr_standard
J 0
(-1100 3750);
PAINT ORANGE (-1100 3750);
DISPLAY INVISIBLE (-1100 3750);
FORCEADD OFFPAGE..1
(-7425 3700);
FORCEPROP 2 LAST $XR3 145 
J 0
(-7766 3664);
DISPLAY 0.638298 (-7766 3664);
PAINT MONO (-7766 3664);
FORCEPROP 2 LAST $XR2 118 
J 0
(-7886 3700);
DISPLAY 0.638298 (-7886 3700);
PAINT MONO (-7886 3700);
FORCEPROP 2 LAST $XR1 133 
J 0
(-7766 3700);
DISPLAY 0.638298 (-7766 3700);
PAINT MONO (-7766 3700);
FORCEPROP 2 LAST $XR0 22 
J 0
(-7646 3700);
DISPLAY 0.638298 (-7646 3700);
PAINT MONO (-7646 3700);
FORCEPROP 1 LAST COMMENT_BODY TRUE
J 0
(-7300 3600);
DISPLAY 1.404255 (-7300 3600);
PAINT PEACH (-7300 3600);
DISPLAY INVISIBLE (-7300 3600);
FORCEPROP 1 LAST OFFPAGE TRUE
J 0
(-7100 3575);
PAINT GREEN (-7100 3575);
DISPLAY INVISIBLE (-7100 3575);
FORCEPROP 2 LAST CDS_LIB mstr_standard
J 0
(-7425 3700);
PAINT ORANGE (-7425 3700);
DISPLAY INVISIBLE (-7425 3700);
FORCEPROP 2 LAST PATH I263
J 0
(-7625 3750);
DISPLAY 1.021277 (-7625 3750);
PAINT ORANGE (-7625 3750);
DISPLAY INVISIBLE (-7625 3750);
FORCEADD OFFPAGE..5
(-6975 2300);
FORCEPROP 2 LAST $XR1 190 
J 0
(-7380 2300);
DISPLAY 0.638298 (-7380 2300);
PAINT MONO (-7380 2300);
FORCEPROP 2 LAST $XR0 133 
J 0
(-7260 2300);
DISPLAY 0.638298 (-7260 2300);
PAINT MONO (-7260 2300);
FORCEPROP 2 LAST PATH I264
J 0
(-7250 2350);
DISPLAY 1.021277 (-7250 2350);
PAINT ORANGE (-7250 2350);
DISPLAY INVISIBLE (-7250 2350);
FORCEPROP 2 LAST CDS_LIB mstr_standard
J 0
(-6975 2300);
PAINT ORANGE (-6975 2300);
DISPLAY INVISIBLE (-6975 2300);
FORCEPROP 1 LAST OFFPAGE TRUE
J 0
(-6650 2175);
DISPLAY 0.872340 (-6650 2175);
PAINT GREEN (-6650 2175);
DISPLAY INVISIBLE (-6650 2175);
FORCEPROP 1 LAST COMMENT_BODY TRUE
J 0
(-6875 2225);
DISPLAY 0.872340 (-6875 2225);
PAINT GREEN (-6875 2225);
DISPLAY INVISIBLE (-6875 2225);
FORCEADD OFFPAGE..1
(-7425 3750);
FORCEPROP 1 LAST COMMENT_BODY TRUE
J 0
(-7300 3650);
DISPLAY 0.872340 (-7300 3650);
PAINT GREEN (-7300 3650);
DISPLAY INVISIBLE (-7300 3650);
FORCEPROP 1 LAST OFFPAGE TRUE
J 0
(-7100 3625);
DISPLAY 0.872340 (-7100 3625);
PAINT GREEN (-7100 3625);
DISPLAY INVISIBLE (-7100 3625);
FORCEPROP 2 LAST PATH I265
J 0
(-6900 3800);
DISPLAY 1.021277 (-6900 3800);
PAINT ORANGE (-6900 3800);
DISPLAY INVISIBLE (-6900 3800);
FORCEPROP 2 LAST CDS_LIB mstr_standard
J 0
(-7425 3750);
PAINT ORANGE (-7425 3750);
DISPLAY INVISIBLE (-7425 3750);
FORCEPROP 2 LAST $XR3 145 
J 0
(-7851 3750);
DISPLAY 0.638298 (-7851 3750);
PAINT MONO (-7851 3750);
DISPLAY INVISIBLE (-7851 3750);
FORCEPROP 2 LAST $XR2 120 
J 0
(-7851 3750);
DISPLAY 0.638298 (-7851 3750);
PAINT MONO (-7851 3750);
DISPLAY INVISIBLE (-7851 3750);
FORCEPROP 2 LAST $XR1 133 
J 0
(-7851 3750);
DISPLAY 0.638298 (-7851 3750);
PAINT MONO (-7851 3750);
DISPLAY INVISIBLE (-7851 3750);
FORCEPROP 2 LAST $XR0 56 
J 0
(-7851 3750);
DISPLAY 0.638298 (-7851 3750);
PAINT MONO (-7851 3750);
DISPLAY INVISIBLE (-7851 3750);
FORCEADD GND..1
(-950 2975);
FORCEPROP 3 LASTPIN (-950 3025) SIG_NAME GND\g
J 0
(-940 3035);
DISPLAY 0.659574 (-940 3035);
PAINT MONO (-940 3035);
DISPLAY INVISIBLE (-940 3035);
FORCEPROP 1 LAST VOLTAGE 0.0V
J 0
(-995 2932);
DISPLAY 0.340426 (-995 2932);
PAINT SKYBLUE (-995 2932);
DISPLAY INVISIBLE (-995 2932);
FORCEPROP 1 LAST HDL_POWER GND
J 0
(-950 3125);
DISPLAY 0.872340 (-950 3125);
PAINT GREEN (-950 3125);
DISPLAY INVISIBLE (-950 3125);
FORCEPROP 2 LAST CDS_LIB mstr_symbols
J 0
(-950 2975);
PAINT ORANGE (-950 2975);
DISPLAY INVISIBLE (-950 2975);
FORCEPROP 1 LAST SIZE 1B
J 0
(-875 2925);
DISPLAY 0.872340 (-875 2925);
PAINT AQUA (-875 2925);
DISPLAY INVISIBLE (-875 2925);
FORCEPROP 1 LAST BODY_TYPE PLUMBING
J 0
(-995 2932);
DISPLAY 0.340426 (-995 2932);
PAINT GREEN (-995 2932);
DISPLAY INVISIBLE (-995 2932);
FORCEPROP 1 LAST PATH I266
J 0
(-875 2975);
DISPLAY 0.872340 (-875 2975);
PAINT AQUA (-875 2975);
DISPLAY INVISIBLE (-875 2975);
FORCEADD OFFPAGE..1
(-6975 1500);
FORCEPROP 2 LAST $XR1 145 
J 0
(-7347 1500);
DISPLAY 0.638298 (-7347 1500);
PAINT MONO (-7347 1500);
FORCEPROP 2 LAST $XR0 191 
J 0
(-7227 1500);
DISPLAY 0.638298 (-7227 1500);
PAINT MONO (-7227 1500);
FORCEPROP 1 LAST OFFPAGE TRUE
J 0
(-6650 1375);
PAINT GREEN (-6650 1375);
DISPLAY INVISIBLE (-6650 1375);
FORCEPROP 1 LAST COMMENT_BODY TRUE
J 0
(-6850 1400);
DISPLAY 1.404255 (-6850 1400);
PAINT PEACH (-6850 1400);
DISPLAY INVISIBLE (-6850 1400);
FORCEPROP 2 LAST PATH I267
J 0
(-6925 1575);
DISPLAY 1.021277 (-6925 1575);
PAINT ORANGE (-6925 1575);
DISPLAY INVISIBLE (-6925 1575);
FORCEPROP 2 LAST CDS_LIB mstr_standard
J 0
(-6975 1500);
PAINT MONO (-6975 1500);
DISPLAY INVISIBLE (-6975 1500);
FORCEADD OFFPAGE..1
(-7625 3050);
FORCEPROP 2 LAST $XR2 170 
J 0
(-8117 3050);
DISPLAY 0.638298 (-8117 3050);
PAINT MONO (-8117 3050);
FORCEPROP 2 LAST $XR1 146 
J 0
(-7997 3050);
DISPLAY 0.638298 (-7997 3050);
PAINT MONO (-7997 3050);
FORCEPROP 2 LAST $XR0 199 
J 0
(-7877 3050);
DISPLAY 0.638298 (-7877 3050);
PAINT MONO (-7877 3050);
FORCEPROP 1 LAST COMMENT_BODY TRUE
J 0
(-7500 2950);
DISPLAY 1.404255 (-7500 2950);
PAINT PEACH (-7500 2950);
DISPLAY INVISIBLE (-7500 2950);
FORCEPROP 1 LAST OFFPAGE TRUE
J 0
(-7300 2925);
PAINT GREEN (-7300 2925);
DISPLAY INVISIBLE (-7300 2925);
FORCEPROP 2 LAST CDS_LIB mstr_standard
J 0
(-7625 3050);
PAINT ORANGE (-7625 3050);
DISPLAY INVISIBLE (-7625 3050);
FORCEPROP 2 LAST PATH I268
J 0
(-7900 3100);
DISPLAY 1.021277 (-7900 3100);
PAINT ORANGE (-7900 3100);
DISPLAY INVISIBLE (-7900 3100);
FORCEADD RES..1
(-6650 3800);
FORCEPROP 1 LAST PART_NUMBER G21497-005
J 0
(-6525 3800);
DISPLAY 0.617021 (-6525 3800);
PAINT BLUE (-6525 3800);
FORCEPROP 1 LAST VALUE 0.0
J 0
(-6725 3700);
DISPLAY 0.617021 (-6725 3700);
PAINT SKYBLUE (-6725 3700);
FORCEPROP 1 LASTPIN (-6550 3800) $PN 2
J 0
(-6588 3812);
DISPLAY 0.617021 (-6588 3812);
PAINT WHITE (-6588 3812);
FORCEPROP 1 LASTPIN (-6750 3800) $PN 1
J 0
(-6738 3812);
DISPLAY 0.617021 (-6738 3812);
PAINT WHITE (-6738 3812);
FORCEPROP 1 LAST TOLERANCE 5%
J 0
(-6725 3650);
DISPLAY 0.617021 (-6725 3650);
PAINT SKYBLUE (-6725 3650);
FORCEPROP 1 LAST PACK_TYPE 0402
J 0
(-6625 3700);
DISPLAY 0.617021 (-6625 3700);
PAINT SKYBLUE (-6625 3700);
FORCEPROP 1 LAST WATTAGE 1/16W
J 0
(-6625 3650);
DISPLAY 0.510638 (-6625 3650);
PAINT SKYBLUE (-6625 3650);
FORCEPROP 1 LAST LOCATION R7W8
J 0
(-6725 3750);
DISPLAY 0.617021 (-6725 3750);
PAINT AQUA (-6725 3750);
FORCEPROP 1 LAST PATH I269
J 0
(-6700 3950);
DISPLAY 0.978723 (-6700 3950);
PAINT WHITE (-6700 3950);
DISPLAY INVISIBLE (-6700 3950);
FORCEPROP 2 LAST CDS_LOCATION R7W8
J 0
(-7125 3800);
DISPLAY 0.617021 (-7125 3800);
PAINT AQUA (-7125 3800);
DISPLAY INVISIBLE (-7125 3800);
FORCEPROP 2 LAST CDS_LIB mstr_discrete
J 0
(-6650 3800);
DISPLAY 1.340426 (-6650 3800);
PAINT ORANGE (-6650 3800);
DISPLAY INVISIBLE (-6650 3800);
FORCEPROP 2 LAST BOM_COST PROC_SIDEBAND
J 0
(-6650 3800);
PAINT MONO (-6650 3800);
DISPLAY INVISIBLE (-6650 3800);
FORCEPROP 1 LAST MATERIAL CHIP
J 0
(-6500 3700);
DISPLAY 0.510638 (-6500 3700);
PAINT SKYBLUE (-6500 3700);
DISPLAY INVISIBLE (-6500 3700);
FORCEPROP 2 LAST ROOM CPU0
J 0
(-6700 3950);
PAINT PEACH (-6700 3950);
DISPLAY INVISIBLE (-6700 3950);
FORCEPROP 2 LAST SEC_TYPE 0402
J 0
(-6700 4025);
DISPLAY 1.021277 (-6700 4025);
PAINT ORANGE (-6700 4025);
DISPLAY INVISIBLE (-6700 4025);
FORCEPROP 2 LAST SEC 1
J 0
(-6700 4025);
DISPLAY 0.680851 (-6700 4025);
PAINT MONO (-6700 4025);
DISPLAY INVISIBLE (-6700 4025);
FORCEPROP 0 LAST CDS_SEC 1
J 0
(-6450 3950);
DISPLAY INVISIBLE (-6450 3950);
FORCEADD RES..1
(-6200 3700);
FORCEPROP 1 LAST LOCATION R7W10
J 0
(-6275 3650);
DISPLAY 0.617021 (-6275 3650);
PAINT AQUA (-6275 3650);
FORCEPROP 1 LAST PACK_TYPE 0402
J 0
(-5750 3650);
DISPLAY 0.617021 (-5750 3650);
PAINT SKYBLUE (-5750 3650);
FORCEPROP 1 LAST TOLERANCE 5%
J 0
(-5650 3650);
DISPLAY 0.617021 (-5650 3650);
PAINT SKYBLUE (-5650 3650);
FORCEPROP 1 LAST WATTAGE 1/16W
J 0
(-5850 3650);
DISPLAY 0.510638 (-5850 3650);
PAINT SKYBLUE (-5850 3650);
FORCEPROP 1 LAST VALUE 0.0
J 0
(-5900 3650);
DISPLAY 0.617021 (-5900 3650);
PAINT SKYBLUE (-5900 3650);
FORCEPROP 1 LASTPIN (-6100 3700) $PN 2
J 0
(-6138 3712);
DISPLAY 0.617021 (-6138 3712);
PAINT WHITE (-6138 3712);
FORCEPROP 1 LAST PART_NUMBER G21497-005
J 0
(-6125 3650);
DISPLAY 0.617021 (-6125 3650);
PAINT BLUE (-6125 3650);
FORCEPROP 1 LASTPIN (-6300 3700) $PN 1
J 0
(-6288 3712);
DISPLAY 0.617021 (-6288 3712);
PAINT WHITE (-6288 3712);
FORCEPROP 2 LAST CDS_LOCATION R7W10
J 0
(-6675 3700);
DISPLAY 0.617021 (-6675 3700);
PAINT AQUA (-6675 3700);
DISPLAY INVISIBLE (-6675 3700);
FORCEPROP 2 LAST CDS_LIB mstr_discrete
J 0
(-6200 3700);
DISPLAY 1.340426 (-6200 3700);
PAINT ORANGE (-6200 3700);
DISPLAY INVISIBLE (-6200 3700);
FORCEPROP 2 LAST BOM_COST PROC_SIDEBAND
J 0
(-6200 3700);
PAINT MONO (-6200 3700);
DISPLAY INVISIBLE (-6200 3700);
FORCEPROP 1 LAST MATERIAL CHIP
J 0
(-6050 3600);
DISPLAY 0.510638 (-6050 3600);
PAINT SKYBLUE (-6050 3600);
DISPLAY INVISIBLE (-6050 3600);
FORCEPROP 2 LAST ROOM CPU0
J 0
(-6250 3850);
PAINT PEACH (-6250 3850);
DISPLAY INVISIBLE (-6250 3850);
FORCEPROP 2 LAST SEC_TYPE 0402
J 0
(-6250 3925);
DISPLAY 1.021277 (-6250 3925);
PAINT ORANGE (-6250 3925);
DISPLAY INVISIBLE (-6250 3925);
FORCEPROP 2 LAST SEC 1
J 0
(-6250 3925);
DISPLAY 0.680851 (-6250 3925);
PAINT MONO (-6250 3925);
DISPLAY INVISIBLE (-6250 3925);
FORCEPROP 0 LAST CDS_SEC 1
J 0
(-6000 3850);
DISPLAY INVISIBLE (-6000 3850);
FORCEPROP 1 LAST PATH I270
J 0
(-6250 3850);
DISPLAY 0.978723 (-6250 3850);
PAINT WHITE (-6250 3850);
DISPLAY INVISIBLE (-6250 3850);
FORCEADD RES..1
(-6400 3750);
FORCEPROP 1 LASTPIN (-6300 3750) $PN 2
J 0
(-6338 3762);
DISPLAY 0.617021 (-6338 3762);
PAINT WHITE (-6338 3762);
FORCEPROP 1 LASTPIN (-6500 3750) $PN 1
J 0
(-6488 3762);
DISPLAY 0.617021 (-6488 3762);
PAINT WHITE (-6488 3762);
FORCEPROP 1 LAST PACK_TYPE 0402
J 0
(-6375 3650);
DISPLAY 0.617021 (-6375 3650);
PAINT SKYBLUE (-6375 3650);
FORCEPROP 1 LAST WATTAGE 1/16W
J 0
(-6375 3600);
DISPLAY 0.510638 (-6375 3600);
PAINT SKYBLUE (-6375 3600);
FORCEPROP 1 LAST TOLERANCE 5%
J 0
(-6475 3600);
DISPLAY 0.617021 (-6475 3600);
PAINT SKYBLUE (-6475 3600);
FORCEPROP 1 LAST VALUE 0.0
J 0
(-6475 3650);
DISPLAY 0.617021 (-6475 3650);
PAINT SKYBLUE (-6475 3650);
FORCEPROP 1 LAST LOCATION R7W12
J 0
(-6475 3700);
DISPLAY 0.617021 (-6475 3700);
PAINT AQUA (-6475 3700);
FORCEPROP 1 LAST PART_NUMBER G21497-005
J 0
(-6275 3750);
DISPLAY 0.617021 (-6275 3750);
PAINT BLUE (-6275 3750);
FORCEPROP 2 LAST CDS_LOCATION R7W12
J 0
(-6875 3750);
DISPLAY 0.617021 (-6875 3750);
PAINT AQUA (-6875 3750);
DISPLAY INVISIBLE (-6875 3750);
FORCEPROP 2 LAST CDS_LIB mstr_discrete
J 0
(-6400 3750);
DISPLAY 1.340426 (-6400 3750);
PAINT ORANGE (-6400 3750);
DISPLAY INVISIBLE (-6400 3750);
FORCEPROP 2 LAST BOM_COST PROC_SIDEBAND
J 0
(-6400 3750);
PAINT MONO (-6400 3750);
DISPLAY INVISIBLE (-6400 3750);
FORCEPROP 1 LAST MATERIAL CHIP
J 0
(-6250 3650);
DISPLAY 0.510638 (-6250 3650);
PAINT SKYBLUE (-6250 3650);
DISPLAY INVISIBLE (-6250 3650);
FORCEPROP 2 LAST ROOM CPU0
J 0
(-6450 3900);
PAINT PEACH (-6450 3900);
DISPLAY INVISIBLE (-6450 3900);
FORCEPROP 2 LAST SEC_TYPE 0402
J 0
(-6450 3975);
DISPLAY 1.021277 (-6450 3975);
PAINT ORANGE (-6450 3975);
DISPLAY INVISIBLE (-6450 3975);
FORCEPROP 2 LAST SEC 1
J 0
(-6450 3975);
DISPLAY 0.680851 (-6450 3975);
PAINT MONO (-6450 3975);
DISPLAY INVISIBLE (-6450 3975);
FORCEPROP 0 LAST CDS_SEC 1
J 0
(-6200 3900);
DISPLAY INVISIBLE (-6200 3900);
FORCEPROP 1 LAST PATH I271
J 0
(-6450 3900);
DISPLAY 0.978723 (-6450 3900);
PAINT WHITE (-6450 3900);
DISPLAY INVISIBLE (-6450 3900);
FORCEADD OFFPAGE..1
R 2
(-300 2800);
FORCEPROP 2 LAST CDS_LIB mstr_standard
J 0
(-300 2800);
PAINT ORANGE (-300 2800);
DISPLAY INVISIBLE (-300 2800);
FORCEPROP 1 LAST OFFPAGE TRUE
J 2
(-625 2675);
PAINT GREEN (-625 2675);
DISPLAY INVISIBLE (-625 2675);
FORCEPROP 1 LAST COMMENT_BODY TRUE
J 2
(-425 2700);
DISPLAY 1.404255 (-425 2700);
PAINT PEACH (-425 2700);
DISPLAY INVISIBLE (-425 2700);
FORCEPROP 2 LAST PATH I272
J 0
(225 2850);
DISPLAY 1.021277 (225 2850);
PAINT ORANGE (225 2850);
DISPLAY INVISIBLE (225 2850);
FORCEPROP 2 LAST $XR3 145 
J 0
(-114 2800);
DISPLAY 0.638298 (-114 2800);
PAINT MONO (-114 2800);
DISPLAY INVISIBLE (-114 2800);
FORCEPROP 2 LAST $XR2 120 
J 0
(-114 2800);
DISPLAY 0.638298 (-114 2800);
PAINT MONO (-114 2800);
DISPLAY INVISIBLE (-114 2800);
FORCEPROP 2 LAST $XR1 133 
J 0
(-114 2800);
DISPLAY 0.638298 (-114 2800);
PAINT MONO (-114 2800);
DISPLAY INVISIBLE (-114 2800);
FORCEPROP 2 LAST $XR0 56 
J 0
(-114 2800);
DISPLAY 0.638298 (-114 2800);
PAINT MONO (-114 2800);
DISPLAY INVISIBLE (-114 2800);
FORCEADD RES..1
(-950 2800);
FORCEPROP 1 LAST PART_NUMBER G21497-005
J 0
(-600 3025);
DISPLAY 0.617021 (-600 3025);
PAINT BLUE (-600 3025);
FORCEPROP 1 LAST TOLERANCE 5%
J 0
(-700 3025);
DISPLAY 0.617021 (-700 3025);
PAINT SKYBLUE (-700 3025);
FORCEPROP 1 LASTPIN (-850 2800) $PN 2
J 0
(-888 2812);
DISPLAY 0.617021 (-888 2812);
PAINT WHITE (-888 2812);
FORCEPROP 1 LASTPIN (-1050 2800) $PN 1
J 0
(-1038 2812);
DISPLAY 0.617021 (-1038 2812);
PAINT WHITE (-1038 2812);
FORCEPROP 1 LAST WATTAGE 1/16W
J 0
(-675 2975);
DISPLAY 0.638298 (-675 2975);
PAINT SKYBLUE (-675 2975);
FORCEPROP 1 LAST PACK_TYPE 0402
J 0
(-800 2975);
DISPLAY 0.617021 (-800 2975);
PAINT SKYBLUE (-800 2975);
FORCEPROP 1 LAST VALUE 0.0
J 0
(-900 2975);
DISPLAY 0.617021 (-900 2975);
PAINT SKYBLUE (-900 2975);
FORCEPROP 1 LAST LOCATION R7W11
J 0
(-900 3025);
DISPLAY 0.617021 (-900 3025);
PAINT AQUA (-900 3025);
FORCEPROP 2 LAST CDS_LOCATION R7W11
J 0
(-1425 2800);
DISPLAY 0.617021 (-1425 2800);
PAINT AQUA (-1425 2800);
DISPLAY INVISIBLE (-1425 2800);
FORCEPROP 0 LAST CDS_SEC 1
J 0
(-750 2950);
DISPLAY INVISIBLE (-750 2950);
FORCEPROP 2 LAST SEC 1
J 0
(-1000 3025);
DISPLAY 0.680851 (-1000 3025);
PAINT MONO (-1000 3025);
DISPLAY INVISIBLE (-1000 3025);
FORCEPROP 2 LAST SEC_TYPE 0402
J 0
(-1000 3025);
DISPLAY 1.021277 (-1000 3025);
PAINT ORANGE (-1000 3025);
DISPLAY INVISIBLE (-1000 3025);
FORCEPROP 2 LAST ROOM CPU0
J 0
(-1000 2950);
PAINT PEACH (-1000 2950);
DISPLAY INVISIBLE (-1000 2950);
FORCEPROP 1 LAST MATERIAL CHIP
J 0
(-800 2700);
DISPLAY 0.510638 (-800 2700);
PAINT SKYBLUE (-800 2700);
DISPLAY INVISIBLE (-800 2700);
FORCEPROP 2 LAST BOM_COST PROC_SIDEBAND
J 0
(-950 2800);
PAINT MONO (-950 2800);
DISPLAY INVISIBLE (-950 2800);
FORCEPROP 2 LAST CDS_LIB mstr_discrete
J 0
(-950 2800);
DISPLAY 1.340426 (-950 2800);
PAINT ORANGE (-950 2800);
DISPLAY INVISIBLE (-950 2800);
FORCEPROP 1 LAST PATH I273
J 0
(-1000 2950);
DISPLAY 0.978723 (-1000 2950);
PAINT WHITE (-1000 2950);
DISPLAY INVISIBLE (-1000 2950);
FORCEADD RES..1
(-6775 2650);
FORCEPROP 1 LAST PART_NUMBER G21497-005
J 0
(-6750 2700);
DISPLAY 0.617021 (-6750 2700);
PAINT BLUE (-6750 2700);
FORCEPROP 1 LAST TOLERANCE 5%
J 0
(-6725 2750);
DISPLAY 0.617021 (-6725 2750);
PAINT SKYBLUE (-6725 2750);
FORCEPROP 1 LAST VALUE 0.0
J 0
(-6825 2750);
DISPLAY 0.617021 (-6825 2750);
PAINT SKYBLUE (-6825 2750);
FORCEPROP 1 LAST WATTAGE 1/16W
J 0
(-6875 2700);
DISPLAY 0.510638 (-6875 2700);
PAINT SKYBLUE (-6875 2700);
FORCEPROP 1 LASTPIN (-6875 2650) $PN 1
J 0
(-6863 2662);
DISPLAY 0.617021 (-6863 2662);
PAINT WHITE (-6863 2662);
FORCEPROP 1 LASTPIN (-6675 2650) $PN 2
J 0
(-6713 2662);
DISPLAY 0.617021 (-6713 2662);
PAINT WHITE (-6713 2662);
FORCEPROP 1 LAST PACK_TYPE 0402
J 0
(-6975 2700);
DISPLAY 0.617021 (-6975 2700);
PAINT SKYBLUE (-6975 2700);
FORCEPROP 1 LAST LOCATION R7W14
J 0
(-6975 2750);
DISPLAY 0.617021 (-6975 2750);
PAINT AQUA (-6975 2750);
FORCEPROP 2 LAST CDS_LOCATION R7W14
J 0
(-7250 2650);
DISPLAY 0.617021 (-7250 2650);
PAINT AQUA (-7250 2650);
DISPLAY INVISIBLE (-7250 2650);
FORCEPROP 2 LAST SEC 1
J 0
(-6825 2875);
DISPLAY 0.680851 (-6825 2875);
PAINT MONO (-6825 2875);
DISPLAY INVISIBLE (-6825 2875);
FORCEPROP 2 LAST SEC_TYPE 0402
J 0
(-6825 2875);
DISPLAY 1.021277 (-6825 2875);
PAINT ORANGE (-6825 2875);
DISPLAY INVISIBLE (-6825 2875);
FORCEPROP 2 LAST ROOM CPU0
J 0
(-6825 2800);
PAINT PEACH (-6825 2800);
DISPLAY INVISIBLE (-6825 2800);
FORCEPROP 1 LAST MATERIAL CHIP
J 0
(-6625 2550);
DISPLAY 0.510638 (-6625 2550);
PAINT SKYBLUE (-6625 2550);
DISPLAY INVISIBLE (-6625 2550);
FORCEPROP 2 LAST BOM_COST PROC_SIDEBAND
J 0
(-6775 2650);
PAINT MONO (-6775 2650);
DISPLAY INVISIBLE (-6775 2650);
FORCEPROP 2 LAST CDS_LIB mstr_discrete
J 0
(-6775 2650);
DISPLAY 1.340426 (-6775 2650);
PAINT ORANGE (-6775 2650);
DISPLAY INVISIBLE (-6775 2650);
FORCEPROP 0 LAST CDS_SEC 1
J 0
(-6800 2800);
DISPLAY INVISIBLE (-6800 2800);
FORCEPROP 1 LAST PATH I274
J 0
(-6825 2800);
DISPLAY 0.978723 (-6825 2800);
PAINT WHITE (-6825 2800);
DISPLAY INVISIBLE (-6825 2800);
FORCEADD RES..2
R 1
(-1400 3050);
FORCEPROP 1 LAST MATERIAL CHIP
J 0
(-1275 3115);
DISPLAY 0.617021 (-1275 3115);
PAINT SKYBLUE (-1275 3115);
FORCEPROP 1 LAST PACK_TYPE 0402
J 0
(-1175 3115);
DISPLAY 0.617021 (-1175 3115);
PAINT SKYBLUE (-1175 3115);
FORCEPROP 1 LAST PART_NUMBER G21796-017
J 0
(-1275 3065);
DISPLAY 0.617021 (-1275 3065);
PAINT BLUE (-1275 3065);
FORCEPROP 1 LAST LOCATION R8C21
J 0
(-1725 3120);
DISPLAY 0.617021 (-1725 3120);
PAINT AQUA (-1725 3120);
FORCEPROP 1 LAST TOLERANCE 1%
J 0
(-1725 3070);
DISPLAY 0.617021 (-1725 3070);
PAINT SKYBLUE (-1725 3070);
FORCEPROP 1 LAST WATTAGE 1/16W
J 0
(-1625 3065);
DISPLAY 0.617021 (-1625 3065);
PAINT SKYBLUE (-1625 3065);
FORCEPROP 1 LASTPIN (-1300 3050) $PN 2
J 0
(-1310 3055);
DISPLAY 0.617021 (-1310 3055);
PAINT ORANGE (-1310 3055);
FORCEPROP 1 LASTPIN (-1500 3050) $PN 1
J 0
(-1487 3055);
DISPLAY 0.617021 (-1487 3055);
PAINT ORANGE (-1487 3055);
FORCEPROP 1 LAST VALUE 100.0
J 0
(-1600 3120);
DISPLAY 0.617021 (-1600 3120);
PAINT SKYBLUE (-1600 3120);
FORCEPROP 1 LAST PATH I275
R 1
J 0
(-1575 3100);
DISPLAY 0.978723 (-1575 3100);
PAINT WHITE (-1575 3100);
DISPLAY INVISIBLE (-1575 3100);
FORCEPROP 0 LAST ROOM SB
R 1
J 0
(-1600 3000);
DISPLAY 1.021277 (-1600 3000);
PAINT ORANGE (-1600 3000);
DISPLAY INVISIBLE (-1600 3000);
FORCEPROP 2 LAST SEC 1
R 1
J 0
(-1625 3100);
DISPLAY 0.680851 (-1625 3100);
PAINT MONO (-1625 3100);
DISPLAY INVISIBLE (-1625 3100);
FORCEPROP 2 LAST SEC_TYPE 0402
R 1
J 0
(-1625 3100);
DISPLAY 1.021277 (-1625 3100);
PAINT ORANGE (-1625 3100);
DISPLAY INVISIBLE (-1625 3100);
FORCEPROP 2 LAST CDS_LOCATION R8C21
R 1
J 0
(-1450 3000);
DISPLAY 0.617021 (-1450 3000);
PAINT AQUA (-1450 3000);
DISPLAY INVISIBLE (-1450 3000);
FORCEPROP 2 LAST CDS_LIB mstr_discrete
R 1
J 0
(-1400 3050);
PAINT ORANGE (-1400 3050);
DISPLAY INVISIBLE (-1400 3050);
FORCEADD RES..1
(-950 2700);
FORCEPROP 1 LAST VALUE 0.0
J 0
(-1050 2600);
DISPLAY 0.617021 (-1050 2600);
PAINT SKYBLUE (-1050 2600);
FORCEPROP 1 LAST LOCATION R7W16
J 0
(-1050 2650);
DISPLAY 0.617021 (-1050 2650);
PAINT AQUA (-1050 2650);
FORCEPROP 1 LASTPIN (-1050 2700) $PN 1
J 0
(-1038 2712);
DISPLAY 0.617021 (-1038 2712);
PAINT WHITE (-1038 2712);
FORCEPROP 1 LAST PACK_TYPE 0402
J 0
(-950 2600);
DISPLAY 0.617021 (-950 2600);
PAINT SKYBLUE (-950 2600);
FORCEPROP 1 LASTPIN (-850 2700) $PN 2
J 0
(-888 2712);
DISPLAY 0.617021 (-888 2712);
PAINT WHITE (-888 2712);
FORCEPROP 1 LAST TOLERANCE 5%
J 0
(-900 2650);
DISPLAY 0.617021 (-900 2650);
PAINT SKYBLUE (-900 2650);
FORCEPROP 1 LAST WATTAGE 1/16W
J 0
(-825 2600);
DISPLAY 0.638298 (-825 2600);
PAINT SKYBLUE (-825 2600);
FORCEPROP 1 LAST PART_NUMBER G21497-005
J 0
(-800 2650);
DISPLAY 0.617021 (-800 2650);
PAINT BLUE (-800 2650);
FORCEPROP 2 LAST CDS_LOCATION R7W16
J 0
(-1425 2700);
DISPLAY 0.617021 (-1425 2700);
PAINT AQUA (-1425 2700);
DISPLAY INVISIBLE (-1425 2700);
FORCEPROP 1 LAST PATH I276
J 0
(-1000 2850);
DISPLAY 0.978723 (-1000 2850);
PAINT WHITE (-1000 2850);
DISPLAY INVISIBLE (-1000 2850);
FORCEPROP 0 LAST CDS_SEC 1
J 0
(-750 2850);
DISPLAY INVISIBLE (-750 2850);
FORCEPROP 2 LAST SEC 1
J 0
(-1000 2925);
DISPLAY 0.680851 (-1000 2925);
PAINT MONO (-1000 2925);
DISPLAY INVISIBLE (-1000 2925);
FORCEPROP 2 LAST SEC_TYPE 0402
J 0
(-1000 2925);
DISPLAY 1.021277 (-1000 2925);
PAINT ORANGE (-1000 2925);
DISPLAY INVISIBLE (-1000 2925);
FORCEPROP 2 LAST ROOM CPU0
J 0
(-1000 2850);
PAINT PEACH (-1000 2850);
DISPLAY INVISIBLE (-1000 2850);
FORCEPROP 1 LAST MATERIAL CHIP
J 0
(-800 2600);
DISPLAY 0.510638 (-800 2600);
PAINT SKYBLUE (-800 2600);
DISPLAY INVISIBLE (-800 2600);
FORCEPROP 2 LAST BOM_COST PROC_SIDEBAND
J 0
(-950 2700);
PAINT MONO (-950 2700);
DISPLAY INVISIBLE (-950 2700);
FORCEPROP 2 LAST CDS_LIB mstr_discrete
J 0
(-950 2700);
DISPLAY 1.340426 (-950 2700);
PAINT ORANGE (-950 2700);
DISPLAY INVISIBLE (-950 2700);
FORCEADD RES..1
(-6850 3050);
FORCEPROP 1 LAST TOLERANCE 5%
J 0
(-6925 2900);
DISPLAY 0.617021 (-6925 2900);
PAINT SKYBLUE (-6925 2900);
FORCEPROP 1 LAST WATTAGE 1/16W
J 0
(-6825 2900);
DISPLAY 0.510638 (-6825 2900);
PAINT SKYBLUE (-6825 2900);
FORCEPROP 1 LAST VALUE 0.0
J 0
(-6925 2950);
DISPLAY 0.617021 (-6925 2950);
PAINT SKYBLUE (-6925 2950);
FORCEPROP 1 LAST PACK_TYPE 0402
J 0
(-6825 2950);
DISPLAY 0.617021 (-6825 2950);
PAINT SKYBLUE (-6825 2950);
FORCEPROP 1 LAST LOCATION R7W18
J 0
(-6925 3000);
DISPLAY 0.617021 (-6925 3000);
PAINT AQUA (-6925 3000);
FORCEPROP 1 LAST PART_NUMBER G21497-005
J 0
(-6950 3100);
DISPLAY 0.617021 (-6950 3100);
PAINT BLUE (-6950 3100);
FORCEPROP 1 LASTPIN (-6950 3050) $PN 1
J 0
(-6938 3062);
DISPLAY 0.617021 (-6938 3062);
PAINT WHITE (-6938 3062);
FORCEPROP 1 LASTPIN (-6750 3050) $PN 2
J 0
(-6788 3062);
DISPLAY 0.617021 (-6788 3062);
PAINT WHITE (-6788 3062);
FORCEPROP 2 LAST CDS_LOCATION R7W18
J 0
(-7325 3050);
DISPLAY 0.617021 (-7325 3050);
PAINT AQUA (-7325 3050);
DISPLAY INVISIBLE (-7325 3050);
FORCEPROP 2 LAST CDS_LIB mstr_discrete
J 0
(-6850 3050);
DISPLAY 1.340426 (-6850 3050);
PAINT ORANGE (-6850 3050);
DISPLAY INVISIBLE (-6850 3050);
FORCEPROP 2 LAST BOM_COST PROC_SIDEBAND
J 0
(-6850 3050);
PAINT MONO (-6850 3050);
DISPLAY INVISIBLE (-6850 3050);
FORCEPROP 1 LAST MATERIAL CHIP
J 0
(-6700 2950);
DISPLAY 0.510638 (-6700 2950);
PAINT SKYBLUE (-6700 2950);
DISPLAY INVISIBLE (-6700 2950);
FORCEPROP 2 LAST ROOM CPU0
J 0
(-6900 3200);
PAINT PEACH (-6900 3200);
DISPLAY INVISIBLE (-6900 3200);
FORCEPROP 2 LAST SEC_TYPE 0402
J 0
(-6900 3275);
DISPLAY 1.021277 (-6900 3275);
PAINT ORANGE (-6900 3275);
DISPLAY INVISIBLE (-6900 3275);
FORCEPROP 2 LAST SEC 1
J 0
(-6900 3275);
DISPLAY 0.680851 (-6900 3275);
PAINT MONO (-6900 3275);
DISPLAY INVISIBLE (-6900 3275);
FORCEPROP 0 LAST CDS_SEC 1
J 0
(-6650 3200);
DISPLAY INVISIBLE (-6650 3200);
FORCEPROP 1 LAST PATH I277
J 0
(-6900 3200);
DISPLAY 0.978723 (-6900 3200);
PAINT WHITE (-6900 3200);
DISPLAY INVISIBLE (-6900 3200);
FORCEADD RES..2
(-6500 4500);
FORCEPROP 1 LASTPIN (-6500 4400) $PN 2
J 0
(-6495 4410);
DISPLAY 0.617021 (-6495 4410);
PAINT ORANGE (-6495 4410);
FORCEPROP 1 LAST MATERIAL CHIP
J 0
(-6460 4425);
DISPLAY 0.617021 (-6460 4425);
PAINT SKYBLUE (-6460 4425);
FORCEPROP 1 LAST WATTAGE 1/16W
J 0
(-6460 4475);
DISPLAY 0.617021 (-6460 4475);
PAINT SKYBLUE (-6460 4475);
FORCEPROP 1 LAST VALUE 4.75K
J 0
(-6455 4575);
DISPLAY 0.617021 (-6455 4575);
PAINT SKYBLUE (-6455 4575);
FORCEPROP 1 LAST PART_NUMBER G21796-072
J 0
(-6460 4375);
DISPLAY 0.617021 (-6460 4375);
PAINT BLUE (-6460 4375);
FORCEPROP 0 LAST POP NOPOP
J 0
(-6450 4275);
DISPLAY 0.638298 (-6450 4275);
PAINT RED (-6450 4275);
FORCEPROP 1 LAST PACK_TYPE 0402
J 0
(-6460 4325);
DISPLAY 0.617021 (-6460 4325);
PAINT SKYBLUE (-6460 4325);
FORCEPROP 1 LAST TOLERANCE 1%
J 0
(-6455 4525);
DISPLAY 0.617021 (-6455 4525);
PAINT SKYBLUE (-6455 4525);
FORCEPROP 1 LASTPIN (-6500 4600) $PN 1
J 0
(-6495 4562);
DISPLAY 0.617021 (-6495 4562);
PAINT ORANGE (-6495 4562);
FORCEPROP 1 LAST LOCATION R7W20
J 0
(-6455 4625);
DISPLAY 0.617021 (-6455 4625);
PAINT AQUA (-6455 4625);
FORCEPROP 2 LAST CDS_LOCATION R7W20
J 0
(-6455 4625);
DISPLAY 0.617021 (-6455 4625);
PAINT AQUA (-6455 4625);
DISPLAY INVISIBLE (-6455 4625);
FORCEPROP 1 LAST PATH I278
J 0
(-6450 4675);
DISPLAY 0.978723 (-6450 4675);
PAINT WHITE (-6450 4675);
DISPLAY INVISIBLE (-6450 4675);
FORCEPROP 2 LAST CDS_LIB mstr_discrete
J 0
(-6500 4500);
PAINT ORANGE (-6500 4500);
DISPLAY INVISIBLE (-6500 4500);
FORCEPROP 0 LAST ROOM CPU0
J 0
(-6450 4725);
DISPLAY 1.021277 (-6450 4725);
PAINT ORANGE (-6450 4725);
DISPLAY INVISIBLE (-6450 4725);
FORCEPROP 2 LAST SEC 1
J 0
(-6450 4725);
DISPLAY 0.680851 (-6450 4725);
PAINT MONO (-6450 4725);
DISPLAY INVISIBLE (-6450 4725);
FORCEPROP 2 LAST SEC_TYPE 0402
J 0
(-6450 4725);
DISPLAY 1.021277 (-6450 4725);
PAINT ORANGE (-6450 4725);
DISPLAY INVISIBLE (-6450 4725);
FORCEADD P3V3_STBY..1
(-6500 4700);
FORCEPROP 3 LASTPIN (-6500 4650) SIG_NAME P3V3_STBY\g
J 0
(-6490 4660);
DISPLAY 0.659574 (-6490 4660);
PAINT MONO (-6490 4660);
DISPLAY INVISIBLE (-6490 4660);
FORCEPROP 1 LAST PATH I279
J 0
(-6455 4702);
DISPLAY 0.340426 (-6455 4702);
PAINT GREEN (-6455 4702);
DISPLAY INVISIBLE (-6455 4702);
FORCEPROP 1 LAST HDL_POWER P3V3_STBY
J 0
(-6800 4575);
DISPLAY 0.872340 (-6800 4575);
PAINT GREEN (-6800 4575);
DISPLAY INVISIBLE (-6800 4575);
FORCEPROP 1 LAST BODY_TYPE PLUMBING
J 0
(-6545 4657);
DISPLAY 0.340426 (-6545 4657);
PAINT GREEN (-6545 4657);
DISPLAY INVISIBLE (-6545 4657);
FORCEPROP 1 LAST SIZE 1B
J 0
(-6455 4722);
DISPLAY 0.340426 (-6455 4722);
PAINT GREEN (-6455 4722);
DISPLAY INVISIBLE (-6455 4722);
FORCEPROP 2 LAST CDS_LIB mstr_symbols
J 0
(-6500 4700);
PAINT ORANGE (-6500 4700);
DISPLAY INVISIBLE (-6500 4700);
FORCEPROP 1 LAST VOLTAGE 3.3V
J 0
(-6545 4657);
DISPLAY 0.340426 (-6545 4657);
PAINT SKYBLUE (-6545 4657);
DISPLAY INVISIBLE (-6545 4657);
FORCEADD OFFPAGE..5
R 2
(-1100 3950);
FORCEPROP 2 LAST $XR0 138 
J 0
(-881 3950);
DISPLAY 0.638298 (-881 3950);
PAINT MONO (-881 3950);
FORCEPROP 2 LAST PATH I4
J 0
(-900 4025);
DISPLAY 1.021277 (-900 4025);
PAINT ORANGE (-900 4025);
DISPLAY INVISIBLE (-900 4025);
FORCEPROP 1 LAST COMMENT_BODY TRUE
J 2
(-1200 3875);
DISPLAY 0.872340 (-1200 3875);
PAINT GREEN (-1200 3875);
DISPLAY INVISIBLE (-1200 3875);
FORCEPROP 1 LAST OFFPAGE TRUE
J 2
(-1425 3825);
DISPLAY 0.872340 (-1425 3825);
PAINT GREEN (-1425 3825);
DISPLAY INVISIBLE (-1425 3825);
FORCEPROP 2 LAST CDS_LIB mstr_standard
J 2
(-1100 3950);
DISPLAY 1.212766 (-1100 3950);
PAINT ORANGE (-1100 3950);
DISPLAY INVISIBLE (-1100 3950);
FORCEADD OFFPAGE..5
(-6275 3150);
FORCEPROP 2 LAST PATH I43
J 0
(-6225 3225);
DISPLAY 1.021277 (-6225 3225);
PAINT ORANGE (-6225 3225);
DISPLAY INVISIBLE (-6225 3225);
FORCEPROP 1 LAST COMMENT_BODY TRUE
J 0
(-6175 3075);
DISPLAY 1.404255 (-6175 3075);
PAINT PEACH (-6175 3075);
DISPLAY INVISIBLE (-6175 3075);
FORCEPROP 1 LAST OFFPAGE TRUE
J 0
(-5950 3025);
PAINT GREEN (-5950 3025);
DISPLAY INVISIBLE (-5950 3025);
FORCEPROP 2 LAST CDS_LIB mstr_standard
J 0
(-6275 3150);
DISPLAY 1.212766 (-6275 3150);
PAINT ORANGE (-6275 3150);
DISPLAY INVISIBLE (-6275 3150);
FORCEPROP 2 LAST $XR0 177 
J 0
(-6704 3150);
DISPLAY 0.638298 (-6704 3150);
PAINT MONO (-6704 3150);
DISPLAY INVISIBLE (-6704 3150);
FORCEADD OFFPAGE..6
R 2
(-1100 4000);
FORCEPROP 2 LAST $XR0 138 
J 0
(-886 4000);
DISPLAY 0.638298 (-886 4000);
PAINT MONO (-886 4000);
FORCEPROP 2 LAST CDS_LIB mstr_standard
J 2
(-1100 4000);
DISPLAY 1.212766 (-1100 4000);
PAINT ORANGE (-1100 4000);
DISPLAY INVISIBLE (-1100 4000);
FORCEPROP 1 LAST OFFPAGE TRUE
J 2
(-1425 3875);
PAINT GREEN (-1425 3875);
DISPLAY INVISIBLE (-1425 3875);
FORCEPROP 1 LAST COMMENT_BODY TRUE
J 2
(-1200 3925);
DISPLAY 1.404255 (-1200 3925);
PAINT PEACH (-1200 3925);
DISPLAY INVISIBLE (-1200 3925);
FORCEPROP 2 LAST PATH I5
J 0
(-900 4075);
DISPLAY 1.021277 (-900 4075);
PAINT ORANGE (-900 4075);
DISPLAY INVISIBLE (-900 4075);
FORCEADD OFFPAGE..5
(-7425 4100);
FORCEPROP 2 LAST $XR0 177 
J 0
(-7680 4100);
DISPLAY 0.638298 (-7680 4100);
PAINT MONO (-7680 4100);
FORCEPROP 2 LAST PATH I53
J 0
(-7375 4175);
DISPLAY 1.021277 (-7375 4175);
PAINT ORANGE (-7375 4175);
DISPLAY INVISIBLE (-7375 4175);
FORCEPROP 1 LAST COMMENT_BODY TRUE
J 0
(-7325 4025);
DISPLAY 1.404255 (-7325 4025);
PAINT PEACH (-7325 4025);
DISPLAY INVISIBLE (-7325 4025);
FORCEPROP 1 LAST OFFPAGE TRUE
J 0
(-7100 3975);
PAINT GREEN (-7100 3975);
DISPLAY INVISIBLE (-7100 3975);
FORCEPROP 2 LAST CDS_LIB mstr_standard
J 0
(-7425 4100);
DISPLAY 1.212766 (-7425 4100);
PAINT ORANGE (-7425 4100);
DISPLAY INVISIBLE (-7425 4100);
FORCEADD OFFPAGE..1
(-7425 3850);
FORCEPROP 2 LAST $XR0 191 
J 0
(-7677 3850);
DISPLAY 0.638298 (-7677 3850);
PAINT MONO (-7677 3850);
FORCEPROP 2 LAST PATH I54
J 0
(-7725 3900);
DISPLAY 1.021277 (-7725 3900);
PAINT ORANGE (-7725 3900);
DISPLAY INVISIBLE (-7725 3900);
FORCEPROP 1 LAST COMMENT_BODY TRUE
J 0
(-7300 3750);
DISPLAY 0.872340 (-7300 3750);
PAINT GREEN (-7300 3750);
DISPLAY INVISIBLE (-7300 3750);
FORCEPROP 1 LAST OFFPAGE TRUE
J 0
(-7100 3725);
DISPLAY 0.872340 (-7100 3725);
PAINT GREEN (-7100 3725);
DISPLAY INVISIBLE (-7100 3725);
FORCEPROP 2 LAST CDS_LIB mstr_standard
J 0
(-7425 3850);
DISPLAY 1.212766 (-7425 3850);
PAINT ORANGE (-7425 3850);
DISPLAY INVISIBLE (-7425 3850);
FORCEADD OFFPAGE..1
(-6975 2250);
FORCEPROP 2 LAST $XR2 190 
J 0
(-7497 2250);
DISPLAY 0.638298 (-7497 2250);
PAINT MONO (-7497 2250);
FORCEPROP 2 LAST $XR1 145 
J 0
(-7377 2250);
DISPLAY 0.638298 (-7377 2250);
PAINT MONO (-7377 2250);
FORCEPROP 2 LAST $XR0 168 
J 0
(-7257 2250);
DISPLAY 0.638298 (-7257 2250);
PAINT MONO (-7257 2250);
FORCEPROP 2 LAST CDS_LIB mstr_standard
J 0
(-6975 2250);
DISPLAY 1.212766 (-6975 2250);
PAINT ORANGE (-6975 2250);
DISPLAY INVISIBLE (-6975 2250);
FORCEPROP 1 LAST OFFPAGE TRUE
J 0
(-6650 2125);
DISPLAY 0.872340 (-6650 2125);
PAINT GREEN (-6650 2125);
DISPLAY INVISIBLE (-6650 2125);
FORCEPROP 1 LAST COMMENT_BODY TRUE
J 0
(-6850 2150);
DISPLAY 0.872340 (-6850 2150);
PAINT GREEN (-6850 2150);
DISPLAY INVISIBLE (-6850 2150);
FORCEPROP 2 LAST PATH I68
J 0
(-7225 2300);
DISPLAY 1.021277 (-7225 2300);
PAINT ORANGE (-7225 2300);
DISPLAY INVISIBLE (-7225 2300);
FORCEADD OFFPAGE..1
(-6975 2200);
FORCEPROP 2 LAST $XR2 170 
J 0
(-7467 2200);
DISPLAY 0.638298 (-7467 2200);
PAINT MONO (-7467 2200);
FORCEPROP 2 LAST $XR1 145 
J 0
(-7347 2200);
DISPLAY 0.638298 (-7347 2200);
PAINT MONO (-7347 2200);
FORCEPROP 2 LAST $XR0 119 
J 0
(-7227 2200);
DISPLAY 0.638298 (-7227 2200);
PAINT MONO (-7227 2200);
FORCEPROP 2 LAST CDS_LIB mstr_standard
J 0
(-6975 2200);
DISPLAY 1.212766 (-6975 2200);
PAINT ORANGE (-6975 2200);
DISPLAY INVISIBLE (-6975 2200);
FORCEPROP 1 LAST OFFPAGE TRUE
J 0
(-6650 2075);
PAINT GREEN (-6650 2075);
DISPLAY INVISIBLE (-6650 2075);
FORCEPROP 1 LAST COMMENT_BODY TRUE
J 0
(-6850 2100);
DISPLAY 1.404255 (-6850 2100);
PAINT PEACH (-6850 2100);
DISPLAY INVISIBLE (-6850 2100);
FORCEPROP 2 LAST PATH I69
J 0
(-7225 2250);
DISPLAY 1.021277 (-7225 2250);
PAINT ORANGE (-7225 2250);
DISPLAY INVISIBLE (-7225 2250);
FORCEADD OFFPAGE..6
R 2
(-1100 3700);
FORCEPROP 2 LAST $XR0 138 
J 0
(-886 3700);
DISPLAY 0.638298 (-886 3700);
PAINT MONO (-886 3700);
FORCEPROP 2 LAST CDS_LIB mstr_standard
J 2
(-1100 3700);
DISPLAY 1.212766 (-1100 3700);
PAINT ORANGE (-1100 3700);
DISPLAY INVISIBLE (-1100 3700);
FORCEPROP 1 LAST OFFPAGE TRUE
J 2
(-1425 3575);
PAINT GREEN (-1425 3575);
DISPLAY INVISIBLE (-1425 3575);
FORCEPROP 1 LAST COMMENT_BODY TRUE
J 2
(-1200 3625);
DISPLAY 1.404255 (-1200 3625);
PAINT PEACH (-1200 3625);
DISPLAY INVISIBLE (-1200 3625);
FORCEPROP 2 LAST PATH I7
J 0
(-900 3775);
DISPLAY 1.021277 (-900 3775);
PAINT ORANGE (-900 3775);
DISPLAY INVISIBLE (-900 3775);
FORCEADD OFFPAGE..5
(-6975 2150);
FORCEPROP 2 LAST $XR2 145 
J 0
(-7500 2150);
DISPLAY 0.638298 (-7500 2150);
PAINT MONO (-7500 2150);
FORCEPROP 2 LAST $XR1 120 
J 0
(-7380 2150);
DISPLAY 0.638298 (-7380 2150);
PAINT MONO (-7380 2150);
FORCEPROP 2 LAST $XR0 133 
J 0
(-7260 2150);
DISPLAY 0.638298 (-7260 2150);
PAINT MONO (-7260 2150);
FORCEPROP 2 LAST CDS_LIB mstr_standard
J 0
(-6975 2150);
DISPLAY 1.212766 (-6975 2150);
PAINT ORANGE (-6975 2150);
DISPLAY INVISIBLE (-6975 2150);
FORCEPROP 1 LAST OFFPAGE TRUE
J 0
(-6650 2025);
PAINT GREEN (-6650 2025);
DISPLAY INVISIBLE (-6650 2025);
FORCEPROP 1 LAST COMMENT_BODY TRUE
J 0
(-6875 2075);
DISPLAY 1.404255 (-6875 2075);
PAINT PEACH (-6875 2075);
DISPLAY INVISIBLE (-6875 2075);
FORCEPROP 2 LAST PATH I70
J 0
(-6925 2225);
DISPLAY 1.021277 (-6925 2225);
PAINT ORANGE (-6925 2225);
DISPLAY INVISIBLE (-6925 2225);
FORCEADD OFFPAGE..5
(-6975 2100);
FORCEPROP 2 LAST $XR0 157 
J 0
(-7260 2100);
DISPLAY 0.638298 (-7260 2100);
PAINT MONO (-7260 2100);
FORCEPROP 2 LAST CDS_LIB mstr_standard
J 0
(-6975 2100);
DISPLAY 1.212766 (-6975 2100);
PAINT ORANGE (-6975 2100);
DISPLAY INVISIBLE (-6975 2100);
FORCEPROP 1 LAST OFFPAGE TRUE
J 0
(-6650 1975);
PAINT GREEN (-6650 1975);
DISPLAY INVISIBLE (-6650 1975);
FORCEPROP 1 LAST COMMENT_BODY TRUE
J 0
(-6875 2025);
DISPLAY 1.404255 (-6875 2025);
PAINT PEACH (-6875 2025);
DISPLAY INVISIBLE (-6875 2025);
FORCEPROP 2 LAST PATH I71
J 0
(-6925 2175);
DISPLAY 1.021277 (-6925 2175);
PAINT ORANGE (-6925 2175);
DISPLAY INVISIBLE (-6925 2175);
FORCEADD OFFPAGE..5
(-6975 2050);
FORCEPROP 2 LAST $XR1 191 
J 0
(-7349 2050);
DISPLAY 0.638298 (-7349 2050);
PAINT MONO (-7349 2050);
FORCEPROP 2 LAST $XR0 89 
J 0
(-7229 2050);
DISPLAY 0.638298 (-7229 2050);
PAINT MONO (-7229 2050);
FORCEPROP 2 LAST CDS_LIB mstr_standard
J 0
(-6975 2050);
DISPLAY 1.212766 (-6975 2050);
PAINT ORANGE (-6975 2050);
DISPLAY INVISIBLE (-6975 2050);
FORCEPROP 1 LAST OFFPAGE TRUE
J 0
(-6650 1925);
PAINT GREEN (-6650 1925);
DISPLAY INVISIBLE (-6650 1925);
FORCEPROP 1 LAST COMMENT_BODY TRUE
J 0
(-6875 1975);
DISPLAY 1.404255 (-6875 1975);
PAINT PEACH (-6875 1975);
DISPLAY INVISIBLE (-6875 1975);
FORCEPROP 2 LAST PATH I72
J 0
(-7225 2100);
DISPLAY 1.021277 (-7225 2100);
PAINT ORANGE (-7225 2100);
DISPLAY INVISIBLE (-7225 2100);
FORCEADD OFFPAGE..1
(-6975 2000);
FORCEPROP 2 LAST $XR1 147 
J 0
(-7377 2000);
DISPLAY 0.638298 (-7377 2000);
PAINT MONO (-7377 2000);
FORCEPROP 2 LAST $XR0 164 
J 0
(-7257 2000);
DISPLAY 0.638298 (-7257 2000);
PAINT MONO (-7257 2000);
FORCEPROP 2 LAST CDS_LIB mstr_standard
J 0
(-6975 2000);
DISPLAY 1.212766 (-6975 2000);
PAINT ORANGE (-6975 2000);
DISPLAY INVISIBLE (-6975 2000);
FORCEPROP 1 LAST OFFPAGE TRUE
J 0
(-6650 1875);
PAINT GREEN (-6650 1875);
DISPLAY INVISIBLE (-6650 1875);
FORCEPROP 1 LAST COMMENT_BODY TRUE
J 0
(-6850 1900);
DISPLAY 1.404255 (-6850 1900);
PAINT PEACH (-6850 1900);
DISPLAY INVISIBLE (-6850 1900);
FORCEPROP 2 LAST PATH I73
J 0
(-6925 2075);
DISPLAY 1.021277 (-6925 2075);
PAINT ORANGE (-6925 2075);
DISPLAY INVISIBLE (-6925 2075);
FORCEADD OFFPAGE..1
(-6975 1900);
FORCEPROP 2 LAST $XR1 147 
J 0
(-7347 1900);
DISPLAY 0.638298 (-7347 1900);
PAINT MONO (-7347 1900);
FORCEPROP 2 LAST $XR0 164 
J 0
(-7227 1900);
DISPLAY 0.638298 (-7227 1900);
PAINT MONO (-7227 1900);
FORCEPROP 2 LAST CDS_LIB mstr_standard
J 0
(-6975 1900);
DISPLAY 1.212766 (-6975 1900);
PAINT ORANGE (-6975 1900);
DISPLAY INVISIBLE (-6975 1900);
FORCEPROP 1 LAST OFFPAGE TRUE
J 0
(-6650 1775);
PAINT GREEN (-6650 1775);
DISPLAY INVISIBLE (-6650 1775);
FORCEPROP 1 LAST COMMENT_BODY TRUE
J 0
(-6850 1800);
DISPLAY 1.404255 (-6850 1800);
PAINT PEACH (-6850 1800);
DISPLAY INVISIBLE (-6850 1800);
FORCEPROP 2 LAST PATH I74
J 0
(-6925 1975);
DISPLAY 1.021277 (-6925 1975);
PAINT ORANGE (-6925 1975);
DISPLAY INVISIBLE (-6925 1975);
FORCEADD OFFPAGE..1
(-6975 1950);
FORCEPROP 2 LAST $XR1 147 
J 0
(-7347 1950);
DISPLAY 0.638298 (-7347 1950);
PAINT MONO (-7347 1950);
FORCEPROP 2 LAST $XR0 164 
J 0
(-7227 1950);
DISPLAY 0.638298 (-7227 1950);
PAINT MONO (-7227 1950);
FORCEPROP 2 LAST CDS_LIB mstr_standard
J 0
(-6975 1950);
DISPLAY 1.212766 (-6975 1950);
PAINT ORANGE (-6975 1950);
DISPLAY INVISIBLE (-6975 1950);
FORCEPROP 1 LAST OFFPAGE TRUE
J 0
(-6650 1825);
PAINT GREEN (-6650 1825);
DISPLAY INVISIBLE (-6650 1825);
FORCEPROP 1 LAST COMMENT_BODY TRUE
J 0
(-6850 1850);
DISPLAY 1.404255 (-6850 1850);
PAINT PEACH (-6850 1850);
DISPLAY INVISIBLE (-6850 1850);
FORCEPROP 2 LAST PATH I75
J 0
(-6925 2025);
DISPLAY 1.021277 (-6925 2025);
PAINT ORANGE (-6925 2025);
DISPLAY INVISIBLE (-6925 2025);
FORCEADD OFFPAGE..1
(-6975 1850);
FORCEPROP 2 LAST $XR1 147 
J 0
(-7347 1850);
DISPLAY 0.638298 (-7347 1850);
PAINT MONO (-7347 1850);
FORCEPROP 2 LAST $XR0 164 
J 0
(-7227 1850);
DISPLAY 0.638298 (-7227 1850);
PAINT MONO (-7227 1850);
FORCEPROP 2 LAST CDS_LIB mstr_standard
J 0
(-6975 1850);
DISPLAY 1.212766 (-6975 1850);
PAINT ORANGE (-6975 1850);
DISPLAY INVISIBLE (-6975 1850);
FORCEPROP 1 LAST OFFPAGE TRUE
J 0
(-6650 1725);
PAINT GREEN (-6650 1725);
DISPLAY INVISIBLE (-6650 1725);
FORCEPROP 1 LAST COMMENT_BODY TRUE
J 0
(-6850 1750);
DISPLAY 1.404255 (-6850 1750);
PAINT PEACH (-6850 1750);
DISPLAY INVISIBLE (-6850 1750);
FORCEPROP 2 LAST PATH I76
J 0
(-6925 1925);
DISPLAY 1.021277 (-6925 1925);
PAINT ORANGE (-6925 1925);
DISPLAY INVISIBLE (-6925 1925);
FORCEADD OFFPAGE..1
(-6975 1800);
FORCEPROP 2 LAST $XR1 147 
J 0
(-7347 1800);
DISPLAY 0.638298 (-7347 1800);
PAINT MONO (-7347 1800);
FORCEPROP 2 LAST $XR0 164 
J 0
(-7227 1800);
DISPLAY 0.638298 (-7227 1800);
PAINT MONO (-7227 1800);
FORCEPROP 2 LAST CDS_LIB mstr_standard
J 0
(-6975 1800);
DISPLAY 1.212766 (-6975 1800);
PAINT ORANGE (-6975 1800);
DISPLAY INVISIBLE (-6975 1800);
FORCEPROP 2 LAST PATH I77
J 0
(-6925 1875);
DISPLAY 1.021277 (-6925 1875);
PAINT ORANGE (-6925 1875);
DISPLAY INVISIBLE (-6925 1875);
FORCEPROP 1 LAST COMMENT_BODY TRUE
J 0
(-6850 1700);
DISPLAY 1.404255 (-6850 1700);
PAINT PEACH (-6850 1700);
DISPLAY INVISIBLE (-6850 1700);
FORCEPROP 1 LAST OFFPAGE TRUE
J 0
(-6650 1675);
PAINT GREEN (-6650 1675);
DISPLAY INVISIBLE (-6650 1675);
FORCEADD CAD_NOTE..1
(-6725 1000);
FORCEPROP 0 LAST L1 PLACE SERIES TERM RES CLOSE TO PCH
J 0
(-6875 875);
DISPLAY 1.021277 (-6875 875);
PAINT ORANGE (-6875 875);
FORCEPROP 1 LAST COMMENT_BODY TRUE
J 0
(-6700 1100);
DISPLAY 0.978723 (-6700 1100);
PAINT ORANGE (-6700 1100);
DISPLAY INVISIBLE (-6700 1100);
FORCEPROP 2 LAST CDS_LIB mstr_symbols
J 0
(-6725 1000);
PAINT MONO (-6725 1000);
DISPLAY INVISIBLE (-6725 1000);
FORCEADD DESIGN_NOTE..1
(-5125 800);
FORCEPROP 0 LAST L1 SMBUS PULL UP AND SERIES RESISTORS ON SEPARATE PAGE
J 0
(-5300 650);
DISPLAY 1.021277 (-5300 650);
PAINT ORANGE (-5300 650);
FORCEPROP 1 LAST COMMENT_BODY TRUE
J 0
(-5100 900);
DISPLAY 0.978723 (-5100 900);
PAINT ORANGE (-5100 900);
DISPLAY INVISIBLE (-5100 900);
FORCEPROP 2 LAST CDS_LIB mstr_symbols
J 0
(-5125 800);
PAINT ORANGE (-5125 800);
DISPLAY INVISIBLE (-5125 800);
FORCEADD INTEL_CORP_BPAGE..1
(0 0);
FORCEPROP 1 LAST CDS_CON_LAST_MODIFIED Fri Jun 16 17:48:47 2017
J 0
(-1425 325);
DISPLAY 1.340426 (-1425 325);
PAINT ORANGE (-1425 325);
DISPLAY INVISIBLE (-1425 325);
FORCEPROP 1 LAST CUSTOM_TXT_CDS <CURRENT_DESIGN_SHEET> OF <TOTAL_DESIGN_SHEETS>
J 0
(-500 25);
PAINT ORANGE (-500 25);
FORCEPROP 1 LAST CUSTOM_TXT_CDS <CON_LAST_MODIFIED>
J 0
(-4000 100);
PAINT ORANGE (-4000 100);
FORCEPROP 2 LAST CUSTOM_TXT_CDS <XR_PAGE_TITLE>
J 0
(-7890 5250);
DISPLAY 0.638298 (-7890 5250);
PAINT PINK (-7890 5250);
DISPLAY INVISIBLE (-7890 5250);
FORCEPROP 1 LAST SCH_TITLE LEWISBURG 7/11 GPIO E-J
J 0
(-7950 50);
DISPLAY 1.212766 (-7950 50);
PAINT YELLOW (-7950 50);
FORCEPROP 2 LAST PAGE_BORDER TRUE
J 0
(-7890 5250);
DISPLAY 0.851064 (-7890 5250);
PAINT PINK (-7890 5250);
DISPLAY INVISIBLE (-7890 5250);
FORCEPROP 2 LAST CDS_LIB mstr_symbols
J 0
(0 0);
PAINT ORANGE (0 0);
DISPLAY INVISIBLE (0 0);
FORCEPROP 1 LAST COMMENT_BODY TRUE
J 0
(12 12);
DISPLAY 0.638298 (12 12);
PAINT PEACH (12 12);
DISPLAY INVISIBLE (12 12);
FORCEPROP 2 LAST CDS_XR_PAGE_TITLE CR-120 : @BASEBOARD_FAB2_LIB.BASEBOARD_FAB2(SCH_1):PAGE120
J 0
(-7890 5250);
DISPLAY 0.638298 (-7890 5250);
PAINT PINK (-7890 5250);
DISPLAY INVISIBLE (-7890 5250);
FORCEADD CAD_NOTE..1
(-1350 3450);
FORCEPROP 0 LAST L2 CLOSE TO PCH
J 0
(-1500 3250);
DISPLAY 1.021277 (-1500 3250);
PAINT ORANGE (-1500 3250);
FORCEPROP 0 LAST L1 PLACE RCOMP RES
J 0
(-1500 3325);
DISPLAY 1.021277 (-1500 3325);
PAINT ORANGE (-1500 3325);
FORCEPROP 2 LAST CDS_LIB mstr_symbols
J 0
(-1350 3450);
PAINT MONO (-1350 3450);
DISPLAY INVISIBLE (-1350 3450);
FORCEPROP 1 LAST COMMENT_BODY TRUE
J 0
(-1325 3550);
DISPLAY 0.978723 (-1325 3550);
PAINT ORANGE (-1325 3550);
DISPLAY INVISIBLE (-1325 3550);
WIRE 16 -1 (-950 3050)(-950 3025);
WIRE 16 -1 (-1300 3050)(-950 3050);
WIRE 16 -1 (-6500 4600)(-6500 4650);
WIRE 16 -1 (-6225 3500)(-5350 3500);
FORCEPROP 0 LAST SIG_NAME IRQ_PCH_NIC_ALERT_N
J 0
(-6225 3510);
DISPLAY 0.617021 (-6225 3510);
PAINT ORANGE (-6225 3510);
WIRE 16 -1 (-7375 4150)(-5350 4150);
FORCEPROP 0 LAST SIG_NAME FM_OC0_USB_N
J 0
(-7375 4160);
DISPLAY 0.617021 (-7375 4160);
PAINT ORANGE (-7375 4160);
WIRE 16 -1 (-7375 4200)(-5350 4200);
FORCEPROP 0 LAST SIG_NAME IRQ_BMC_PCH_SCI_LPC_N
J 0
(-7375 4210);
DISPLAY 0.617021 (-7375 4210);
PAINT ORANGE (-7375 4210);
WIRE 16 -1 (-7375 4100)(-5350 4100);
FORCEPROP 0 LAST SIG_NAME LED_PCH_SATA_HDD_N
J 0
(-7375 4110);
DISPLAY 0.617021 (-7375 4110);
PAINT ORANGE (-7375 4110);
WIRE 16 -1 (-7375 3950)(-5350 3950);
FORCEPROP 0 LAST SIG_NAME FM_CPU_MSMI_LVT3_N
J 0
(-7375 3960);
DISPLAY 0.617021 (-7375 3960);
PAINT ORANGE (-7375 3960);
WIRE 16 -1 (-7375 3700)(-6300 3700);
FORCEPROP 2 LAST SIG_NAME FM_CPU0_RC_ERROR_N
J 0
(-7375 3710);
DISPLAY 0.617021 (-7375 3710);
PAINT ORANGE (-7375 3710);
WIRE 3 682 (-7525 3650)(-7525 3600);
WIRE 3 682 (-6775 3650)(-7525 3650);
WIRE 3 682 (-6775 3775)(-6775 3650);
WIRE 16 -1 (-7375 3750)(-6500 3750);
FORCEPROP 2 LAST SIG_NAME FM_CPU1_RC_ERROR_N
J 0
(-7375 3760);
DISPLAY 0.617021 (-7375 3760);
PAINT ORANGE (-7375 3760);
WIRE 16 -1 (-7375 3800)(-6750 3800);
FORCEPROP 0 LAST SIG_NAME FM_POST_CARD_PRES_BMC_N
J 0
(-7375 3810);
DISPLAY 0.617021 (-7375 3810);
PAINT ORANGE (-7375 3810);
WIRE 16 -1 (-7375 3850)(-6750 3850);
FORCEPROP 0 LAST SIG_NAME FM_CPLD_ADR_TRIGGER_N
J 0
(-7375 3860);
DISPLAY 0.617021 (-7375 3860);
PAINT ORANGE (-7375 3860);
WIRE 16 -1 (-7375 3900)(-5350 3900);
FORCEPROP 0 LAST SIG_NAME FM_CPU_ERR2_LVT3_N
J 0
(-7375 3910);
DISPLAY 0.617021 (-7375 3910);
PAINT ORANGE (-7375 3910);
WIRE 16 -1 (-7375 4000)(-5350 4000);
FORCEPROP 0 LAST SIG_NAME IRQ_BMC_PCH_NMI_STBY_N
J 0
(-7375 4010);
DISPLAY 0.617021 (-7375 4010);
PAINT ORANGE (-7375 4010);
WIRE 16 -1 (-7375 4050)(-5350 4050);
FORCEPROP 0 LAST SIG_NAME FM_ADR_SMI_GPIO_N
J 0
(-7375 4060);
DISPLAY 0.617021 (-7375 4060);
PAINT ORANGE (-7375 4060);
WIRE 16 -1 (-7375 4250)(-5350 4250);
FORCEPROP 0 LAST SIG_NAME IRQ_BMC_PCH_SMI_LPC_N
J 0
(-7375 4260);
DISPLAY 0.617021 (-7375 4260);
PAINT ORANGE (-7375 4260);
WIRE 16 -1 (-7375 4300)(-5350 4300);
FORCEPROP 0 LAST SIG_NAME IRQ_UV_DETECT_N
J 0
(-7375 4310);
DISPLAY 0.617021 (-7375 4310);
PAINT ORANGE (-7375 4310);
WIRE 16 -1 (-6550 3850)(-5350 3850);
FORCEPROP 0 LAST SIG_NAME FM_CPLD_ADR_TRIGGER_R_N
J 0
(-6185 3860);
DISPLAY 0.617021 (-6185 3860);
PAINT ORANGE (-6185 3860);
FORCEPROP 2 LASTPROP $XRERR UNIQUE?
J 0
(-6425 3860);
DISPLAY 0.638298 (-6425 3860);
PAINT MONO (-6425 3860);
DISPLAY INVISIBLE (-6425 3860);
WIRE 16 -1 (-6500 3800)(-6550 3800);
WIRE 16 -1 (-6500 4400)(-6500 3800);
WIRE 16 -1 (-5350 3800)(-6500 3800);
FORCEPROP 0 LAST SIG_NAME FM_POST_CARD_PRES_BMC_R1_N
J 0
(-6175 3810);
DISPLAY 0.617021 (-6175 3810);
PAINT ORANGE (-6175 3810);
FORCEPROP 2 LASTPROP $XRERR UNIQUE?
J 0
(-6415 3810);
DISPLAY 0.638298 (-6415 3810);
PAINT MONO (-6415 3810);
DISPLAY INVISIBLE (-6415 3810);
WIRE 16 -1 (-6225 3100)(-5350 3100);
FORCEPROP 0 LAST SIG_NAME SGPIO_PCH_SATA_DOUT0
J 0
(-6225 3110);
DISPLAY 0.617021 (-6225 3110);
PAINT ORANGE (-6225 3110);
WIRE 16 -1 (-6225 3150)(-5350 3150);
FORCEPROP 0 LAST SIG_NAME LED_PCH_SSATA_HDD_N
J 0
(-6225 3160);
DISPLAY 0.617021 (-6225 3160);
PAINT ORANGE (-6225 3160);
WIRE 16 -1 (-6225 3300)(-5350 3300);
FORCEPROP 0 LAST SIG_NAME FM_BIOS_TOP_SWAP
J 0
(-6225 3310);
DISPLAY 0.617021 (-6225 3310);
PAINT ORANGE (-6225 3310);
WIRE 16 -1 (-6225 3250)(-5350 3250);
FORCEPROP 0 LAST SIG_NAME FM_IE_DISABLE_N
J 0
(-6225 3260);
DISPLAY 0.617021 (-6225 3260);
PAINT ORANGE (-6225 3260);
WIRE 16 -1 (-5350 3050)(-6750 3050);
FORCEPROP 2 LAST SIG_NAME IRQ_SML1_PMBUS_ALERT_R1_N
J 0
(-6225 3060);
DISPLAY 0.617021 (-6225 3060);
PAINT ORANGE (-6225 3060);
FORCEPROP 2 LASTPROP $XRERR UNIQUE?
J 0
(-6465 3060);
DISPLAY 0.638298 (-6465 3060);
PAINT MONO (-6465 3060);
DISPLAY INVISIBLE (-6465 3060);
WIRE 16 -1 (-6225 2950)(-5350 2950);
FORCEPROP 0 LAST SIG_NAME SGPIO_PCH_SATA_CLOCK
J 0
(-6225 2960);
DISPLAY 0.617021 (-6225 2960);
PAINT ORANGE (-6225 2960);
WIRE 16 -1 (-6225 2750)(-5350 2750);
FORCEPROP 0 LAST SIG_NAME JTAG_PCH_PLD_TCK
J 0
(-6225 2760);
DISPLAY 0.617021 (-6225 2760);
PAINT ORANGE (-6225 2760);
WIRE 16 -1 (-6225 2800)(-5350 2800);
FORCEPROP 0 LAST SIG_NAME JTAG_PCH_PLD_TDI
J 0
(-6225 2810);
DISPLAY 0.617021 (-6225 2810);
PAINT ORANGE (-6225 2810);
WIRE 16 -1 (-6225 2850)(-5350 2850);
FORCEPROP 0 LAST SIG_NAME JTAG_PCH_PLD_TMS
J 0
(-6225 2860);
DISPLAY 0.617021 (-6225 2860);
PAINT ORANGE (-6225 2860);
WIRE 16 -1 (-6225 2900)(-5350 2900);
FORCEPROP 0 LAST SIG_NAME JTAG_PCH_PLD_TDO
J 0
(-6225 2910);
DISPLAY 0.617021 (-6225 2910);
PAINT ORANGE (-6225 2910);
WIRE 16 -1 (-6225 3000)(-5350 3000);
FORCEPROP 0 LAST SIG_NAME SGPIO_PCH_SATA_LOAD
J 0
(-6225 3010);
DISPLAY 0.617021 (-6225 3010);
PAINT ORANGE (-6225 3010);
WIRE 16 -1 (-5350 2650)(-6675 2650);
FORCEPROP 0 LAST SIG_NAME FM_BMC_READY_R1_N
J 0
(-6225 2660);
DISPLAY 0.617021 (-6225 2660);
PAINT ORANGE (-6225 2660);
FORCEPROP 2 LASTPROP $XRERR UNIQUE?
J 0
(-6465 2660);
DISPLAY 0.638298 (-6465 2660);
PAINT MONO (-6465 2660);
DISPLAY INVISIBLE (-6465 2660);
WIRE 16 -1 (-6225 2500)(-5350 2500);
FORCEPROP 0 LAST SIG_NAME FM_HSC_TIMER_EXP_N
J 0
(-6225 2510);
DISPLAY 0.617021 (-6225 2510);
PAINT ORANGE (-6225 2510);
WIRE 16 -1 (-6925 2350)(-5350 2350);
FORCEPROP 2 LAST SIG_NAME FM_UARTSW_MSB_N
J 0
(-6925 2360);
DISPLAY 0.617021 (-6925 2360);
PAINT ORANGE (-6925 2360);
WIRE 16 -1 (-6925 2300)(-5350 2300);
FORCEPROP 2 LAST SIG_NAME FM_CPU0_RC_EN
J 0
(-6925 2310);
DISPLAY 0.617021 (-6925 2310);
PAINT ORANGE (-6925 2310);
WIRE 16 -1 (-6925 2250)(-5350 2250);
FORCEPROP 2 LAST SIG_NAME FM_SOL_UART_CH_SEL
J 0
(-6925 2260);
DISPLAY 0.617021 (-6925 2260);
PAINT ORANGE (-6925 2260);
WIRE 16 -1 (-6925 2150)(-5350 2150);
FORCEPROP 2 LAST SIG_NAME FM_BIOS_SMI_ACTIVE_N
J 0
(-6925 2160);
DISPLAY 0.617021 (-6925 2160);
PAINT ORANGE (-6925 2160);
WIRE 16 -1 (-6925 2100)(-5350 2100);
FORCEPROP 2 LAST SIG_NAME FM_NMI_EVENT_N
J 0
(-6925 2110);
DISPLAY 0.617021 (-6925 2110);
PAINT ORANGE (-6925 2110);
WIRE 16 -1 (-6925 1950)(-5350 1950);
FORCEPROP 0 LAST SIG_NAME FM_BOARD_SKU_ID3
J 0
(-6925 1960);
DISPLAY 0.617021 (-6925 1960);
PAINT ORANGE (-6925 1960);
WIRE 16 -1 (-6925 1900)(-5350 1900);
FORCEPROP 0 LAST SIG_NAME FM_BOARD_SKU_ID2
J 0
(-6925 1910);
DISPLAY 0.617021 (-6925 1910);
PAINT ORANGE (-6925 1910);
WIRE 16 -1 (-6925 1850)(-5350 1850);
FORCEPROP 0 LAST SIG_NAME FM_BOARD_SKU_ID1
J 0
(-6925 1860);
DISPLAY 0.617021 (-6925 1860);
PAINT ORANGE (-6925 1860);
WIRE 16 -1 (-2150 1250)(-1375 1250);
FORCEPROP 2 LAST SIG_NAME LED_GBE_P0_0
J 0
(-2000 1260);
DISPLAY 0.617021 (-2000 1260);
PAINT ORANGE (-2000 1260);
WIRE 16 -1 (-2150 1350)(-1375 1350);
FORCEPROP 2 LAST SIG_NAME LED_GBE_P1_0
J 0
(-2000 1360);
DISPLAY 0.617021 (-2000 1360);
PAINT ORANGE (-2000 1360);
WIRE 16 -1 (-2150 1400)(-1375 1400);
FORCEPROP 2 LAST SIG_NAME LED_GBE_P1_1
J 0
(-2000 1410);
DISPLAY 0.617021 (-2000 1410);
PAINT ORANGE (-2000 1410);
WIRE 16 -1 (-6225 2700)(-5350 2700);
FORCEPROP 0 LAST SIG_NAME FM_BIOS_USB_RECOVERY
J 0
(-6225 2710);
DISPLAY 0.617021 (-6225 2710);
PAINT ORANGE (-6225 2710);
WIRE 16 -1 (-7575 3050)(-6950 3050);
FORCEPROP 2 LAST SIG_NAME IRQ_SML1_PMBUS_ALERT_N
J 0
(-7575 3060);
DISPLAY 0.617021 (-7575 3060);
PAINT ORANGE (-7575 3060);
WIRE 16 -1 (-6225 3450)(-5350 3450);
FORCEPROP 0 LAST SIG_NAME SMB_LAN_STBY_LVC3_SDA_R2
J 0
(-6225 3460);
DISPLAY 0.617021 (-6225 3460);
PAINT ORANGE (-6225 3460);
WIRE 16 -1 (-5350 3700)(-6100 3700);
FORCEPROP 2 LAST SIG_NAME FM_CPU0_RC_ERROR_R1_N
J 0
(-6050 3710);
DISPLAY 0.617021 (-6050 3710);
PAINT ORANGE (-6050 3710);
FORCEPROP 2 LASTPROP $XRERR UNIQUE?
J 0
(-6290 3710);
DISPLAY 0.638298 (-6290 3710);
PAINT MONO (-6290 3710);
DISPLAY INVISIBLE (-6290 3710);
WIRE 16 -1 (-6225 3600)(-5350 3600);
FORCEPROP 0 LAST SIG_NAME SGPIO_PCH_SSATA_LOAD
J 0
(-6225 3610);
DISPLAY 0.617021 (-6225 3610);
PAINT ORANGE (-6225 3610);
WIRE 16 -1 (-6225 3550)(-5350 3550);
FORCEPROP 0 LAST SIG_NAME SGPIO_PCH_SSATA_CLOCK
J 0
(-6225 3560);
DISPLAY 0.617021 (-6225 3560);
PAINT ORANGE (-6225 3560);
WIRE 16 -1 (-5350 3750)(-6300 3750);
FORCEPROP 2 LAST SIG_NAME FM_CPU1_RC_ERROR_R1_N
J 0
(-6050 3760);
DISPLAY 0.617021 (-6050 3760);
PAINT ORANGE (-6050 3760);
FORCEPROP 2 LASTPROP $XRERR UNIQUE?
J 0
(-6290 3760);
DISPLAY 0.638298 (-6290 3760);
PAINT MONO (-6290 3760);
DISPLAY INVISIBLE (-6290 3760);
WIRE 16 -1 (-2150 4200)(-1150 4200);
FORCEPROP 0 LAST SIG_NAME FM_BIOS_SMI_ACTIVE_N
J 0
(-2000 4210);
DISPLAY 0.617021 (-2000 4210);
PAINT ORANGE (-2000 4210);
WIRE 16 -1 (-350 2800)(-850 2800);
FORCEPROP 0 LAST SIG_NAME FM_CPU1_RC_ERROR_N
J 0
(-850 2810);
DISPLAY 0.617021 (-850 2810);
PAINT ORANGE (-850 2810);
WIRE 16 -1 (-850 2700)(-350 2700);
FORCEPROP 0 LAST SIG_NAME IRQ_DIMM_SAVE_LVT3_N
J 0
(-850 2710);
DISPLAY 0.617021 (-850 2710);
PAINT ORANGE (-850 2710);
WIRE 16 -1 (-6925 2200)(-5350 2200);
FORCEPROP 2 LAST SIG_NAME IRQ_FORCE_NM_THROTTLE_N
J 0
(-6925 2210);
DISPLAY 0.617021 (-6925 2210);
PAINT ORANGE (-6925 2210);
WIRE 16 -1 (-6225 3200)(-5350 3200);
FORCEPROP 0 LAST SIG_NAME FM_FORCE_ADR_N
J 0
(-6225 3210);
DISPLAY 0.617021 (-6225 3210);
PAINT ORANGE (-6225 3210);
WIRE 16 -1 (-2150 3200)(-1150 3200);
FORCEPROP 0 LAST SIG_NAME FM_BACKUP_BIOS_SEL_N
J 0
(-2000 3210);
DISPLAY 0.617021 (-2000 3210);
PAINT ORANGE (-2000 3210);
WIRE 16 -1 (-2150 3150)(-1150 3150);
FORCEPROP 0 LAST SIG_NAME FM_UARTSW_LSB_N
J 0
(-2000 3160);
DISPLAY 0.617021 (-2000 3160);
PAINT ORANGE (-2000 3160);
WIRE 16 -1 (-6225 3350)(-5350 3350);
FORCEPROP 0 LAST SIG_NAME FM_MEM_THERM_EVENT_PCH_N
J 0
(-6225 3360);
DISPLAY 0.617021 (-6225 3360);
PAINT ORANGE (-6225 3360);
WIRE 16 -1 (-6225 2550)(-5350 2550);
FORCEPROP 0 LAST SIG_NAME FM_MP_PS_FAIL_N
J 0
(-6225 2560);
DISPLAY 0.617021 (-6225 2560);
PAINT ORANGE (-6225 2560);
WIRE 16 -1 (-6225 2600)(-5350 2600);
FORCEPROP 0 LAST SIG_NAME FM_MP_PS_REDUNDANT_LOST_N
J 0
(-6225 2610);
DISPLAY 0.617021 (-6225 2610);
PAINT ORANGE (-6225 2610);
WIRE 16 -1 (-6225 3400)(-5350 3400);
FORCEPROP 0 LAST SIG_NAME SMB_LAN_STBY_LVC3_SCL_R2
J 0
(-6225 3410);
DISPLAY 0.617021 (-6225 3410);
PAINT ORANGE (-6225 3410);
WIRE 3 682 (-7700 3100)(-7700 3150);
WIRE 16 -1 (-2150 2850)(-1375 2850);
FORCEPROP 0 LAST SIG_NAME JTAG_PCH_GBE_TRST_N
J 0
(-2000 2860);
DISPLAY 0.617021 (-2000 2860);
PAINT ORANGE (-2000 2860);
WIRE 16 -1 (-2150 2800)(-1050 2800);
FORCEPROP 0 LAST SIG_NAME FM_CPU1_RC_ERROR_R_N
J 0
(-2000 2810);
DISPLAY 0.617021 (-2000 2810);
PAINT ORANGE (-2000 2810);
FORCEPROP 2 LASTPROP $XRERR UNIQUE?
J 0
(-2240 2810);
DISPLAY 0.638298 (-2240 2810);
PAINT MONO (-2240 2810);
DISPLAY INVISIBLE (-2240 2810);
WIRE 16 -1 (-2150 2700)(-1050 2700);
FORCEPROP 0 LAST SIG_NAME IRQ_DIMM_SAVE_LVT3_R_N
J 0
(-2000 2710);
DISPLAY 0.617021 (-2000 2710);
PAINT ORANGE (-2000 2710);
FORCEPROP 2 LASTPROP $XRERR UNIQUE?
J 0
(-2240 2710);
DISPLAY 0.638298 (-2240 2710);
PAINT MONO (-2240 2710);
DISPLAY INVISIBLE (-2240 2710);
WIRE 16 -1 (-2150 2500)(-1500 2500);
FORCEPROP 0 LAST SIG_NAME JTAG_PCH_GBE_TDO
J 0
(-2000 2510);
DISPLAY 0.617021 (-2000 2510);
PAINT ORANGE (-2000 2510);
WIRE 16 -1 (-2150 2300)(-1400 2300);
FORCEPROP 2 LAST SIG_NAME TP_PCH_GPP_J21
J 0
(-2000 2310);
DISPLAY 0.617021 (-2000 2310);
PAINT ORANGE (-2000 2310);
FORCEPROP 2 LASTPROP $XRERR UNIQUE?
J 0
(-1370 2300);
DISPLAY 0.638298 (-1370 2300);
PAINT MONO (-1370 2300);
DISPLAY INVISIBLE (-1370 2300);
WIRE 16 -1 (-2150 2250)(-1350 2250);
FORCEPROP 0 LAST SIG_NAME FM_GBE2_LVC3_MOD_ABS
J 0
(-2000 2260);
DISPLAY 0.617021 (-2000 2260);
PAINT ORANGE (-2000 2260);
WIRE 16 -1 (-2150 2750)(-1375 2750);
FORCEPROP 0 LAST SIG_NAME IRQ_BOARD_BMC_ALERT_N
J 0
(-2000 2760);
DISPLAY 0.617021 (-2000 2760);
PAINT ORANGE (-2000 2760);
WIRE 16 -1 (-2150 2650)(-1500 2650);
FORCEPROP 0 LAST SIG_NAME JTAG_PCH_GBE_TDI
J 0
(-2000 2660);
DISPLAY 0.617021 (-2000 2660);
PAINT ORANGE (-2000 2660);
WIRE 16 -1 (-2150 2600)(-1500 2600);
FORCEPROP 0 LAST SIG_NAME JTAG_PCH_GBE_TMS
J 0
(-2000 2610);
DISPLAY 0.617021 (-2000 2610);
PAINT ORANGE (-2000 2610);
WIRE 16 -1 (-2150 2550)(-1500 2550);
FORCEPROP 0 LAST SIG_NAME JTAG_PCH_GBE_CLK
J 0
(-2000 2560);
DISPLAY 0.617021 (-2000 2560);
PAINT ORANGE (-2000 2560);
WIRE 16 -1 (-2150 3650)(-1150 3650);
FORCEPROP 0 LAST SIG_NAME SMB_VR_STBY_LVC3_SCL_R1
J 0
(-2000 3660);
DISPLAY 0.617021 (-2000 3660);
PAINT ORANGE (-2000 3660);
WIRE 16 -1 (-2150 2950)(-1375 2950);
FORCEPROP 0 LAST SIG_NAME FM_10GBE_LOM_DISABLE_N
J 0
(-2000 2960);
DISPLAY 0.617021 (-2000 2960);
PAINT ORANGE (-2000 2960);
WIRE 16 -1 (-2150 2900)(-1375 2900);
FORCEPROP 0 LAST SIG_NAME PU_10GBE_LOM_PCI_DISABLE_N
J 0
(-2000 2910);
DISPLAY 0.617021 (-2000 2910);
PAINT ORANGE (-2000 2910);
WIRE 16 -1 (-2150 3000)(-1375 3000);
FORCEPROP 0 LAST SIG_NAME FM_BIOS_MRC_DEBUG_MSG_DIS_N
J 0
(-2000 3010);
DISPLAY 0.617021 (-2000 3010);
PAINT ORANGE (-2000 3010);
WIRE 16 -1 (-2150 2350)(-1350 2350);
FORCEPROP 0 LAST SIG_NAME FM_GBE3_LVC3_MOD_ABS
J 0
(-2000 2360);
DISPLAY 0.617021 (-2000 2360);
PAINT ORANGE (-2000 2360);
WIRE 16 -1 (-2150 2000)(-1400 2000);
FORCEPROP 0 LAST SIG_NAME SMB_PCH_MEZZ_LOM3_SDA
J 0
(-2000 2010);
DISPLAY 0.617021 (-2000 2010);
PAINT ORANGE (-2000 2010);
WIRE 16 -1 (-2150 1900)(-1400 1900);
FORCEPROP 0 LAST SIG_NAME SMB_PCH_MEZZ_LOM2_SDA
J 0
(-2000 1910);
DISPLAY 0.617021 (-2000 1910);
PAINT ORANGE (-2000 1910);
WIRE 3 682 (-1950 3250)(-2000 3250);
WIRE 3 682 (-1950 3600)(-1950 3250);
WIRE 3 682 (-2000 3600)(-1950 3600);
WIRE 3 682 (-1900 3600)(-1950 3600);
WIRE 16 -1 (-2150 3700)(-1150 3700);
FORCEPROP 0 LAST SIG_NAME SMB_VR_STBY_LVC3_SDA_R1
J 0
(-2000 3710);
DISPLAY 0.617021 (-2000 3710);
PAINT ORANGE (-2000 3710);
WIRE 16 -1 (-2150 3900)(-1150 3900);
FORCEPROP 0 LAST SIG_NAME PU_ADR_TIMER_HOLD_OFF_N
J 0
(-2000 3910);
DISPLAY 0.617021 (-2000 3910);
PAINT ORANGE (-2000 3910);
WIRE 16 -1 (-2150 3950)(-1150 3950);
FORCEPROP 0 LAST SIG_NAME SMB_LAN_STBY_LVC3_SCL_R1
J 0
(-2000 3960);
DISPLAY 0.617021 (-2000 3960);
PAINT ORANGE (-2000 3960);
WIRE 16 -1 (-2150 3050)(-1500 3050);
FORCEPROP 2 LAST SIG_NAME A_RCOMP_3P3
J 0
(-2000 3060);
DISPLAY 0.617021 (-2000 3060);
PAINT ORANGE (-2000 3060);
FORCEPROP 2 LASTPROP $XRERR UNIQUE?
J 0
(-2240 3060);
DISPLAY 0.638298 (-2240 3060);
PAINT MONO (-2240 3060);
DISPLAY INVISIBLE (-2240 3060);
WIRE 16 -1 (-7300 2650)(-6875 2650);
FORCEPROP 0 LAST SIG_NAME FM_BMC_READY_N
J 0
(-7300 2660);
DISPLAY 0.617021 (-7300 2660);
PAINT ORANGE (-7300 2660);
WIRE 16 -1 (-6225 2450)(-5350 2450);
FORCEPROP 0 LAST SIG_NAME IRQ_OC_DETECT_N
J 0
(-6225 2460);
DISPLAY 0.617021 (-6225 2460);
PAINT ORANGE (-6225 2460);
WIRE 16 -1 (-6000 2050)(-5350 2050);
FORCEPROP 2 LAST SIG_NAME FM_ADR_COMPLETE_R1
J 0
(-5960 2060);
DISPLAY 0.617021 (-5960 2060);
PAINT ORANGE (-5960 2060);
FORCEPROP 2 LASTPROP $XRERR UNIQUE?
J 0
(-6200 2060);
DISPLAY 0.638298 (-6200 2060);
PAINT MONO (-6200 2060);
DISPLAY INVISIBLE (-6200 2060);
WIRE 16 -1 (-6925 1800)(-5350 1800);
FORCEPROP 0 LAST SIG_NAME FM_BOARD_SKU_ID0
J 0
(-6925 1810);
DISPLAY 0.617021 (-6925 1810);
PAINT ORANGE (-6925 1810);
WIRE 16 -1 (-2150 4300)(-1150 4300);
FORCEPROP 0 LAST SIG_NAME FM_SSATA_PCIE_M2_SEL
J 0
(-2000 4310);
DISPLAY 0.617021 (-2000 4310);
PAINT ORANGE (-2000 4310);
WIRE 16 -1 (-2150 4250)(-1150 4250);
FORCEPROP 0 LAST SIG_NAME FM_PCH_BMC_THERMTRIP_N
J 0
(-2000 4260);
DISPLAY 0.617021 (-2000 4260);
PAINT ORANGE (-2000 4260);
WIRE 16 -1 (-2150 4150)(-1150 4150);
FORCEPROP 0 LAST SIG_NAME FM_BMC_NMI_N
J 0
(-2000 4160);
DISPLAY 0.617021 (-2000 4160);
PAINT ORANGE (-2000 4160);
WIRE 16 -1 (-2150 4100)(-1150 4100);
FORCEPROP 0 LAST SIG_NAME FP_PWR_ID_LED_N
J 0
(-2000 4110);
DISPLAY 0.617021 (-2000 4110);
PAINT ORANGE (-2000 4110);
WIRE 16 -1 (-2150 4050)(-1150 4050);
FORCEPROP 0 LAST SIG_NAME FM_OC_DETECT_EN_N
J 0
(-2000 4060);
DISPLAY 0.617021 (-2000 4060);
PAINT ORANGE (-2000 4060);
WIRE 16 -1 (-2150 4000)(-1150 4000);
FORCEPROP 0 LAST SIG_NAME SMB_LAN_STBY_LVC3_SDA_R1
J 0
(-2000 4010);
DISPLAY 0.617021 (-2000 4010);
PAINT ORANGE (-2000 4010);
WIRE 16 -1 (-2150 3750)(-1150 3750);
FORCEPROP 0 LAST SIG_NAME FM_FLASH_ATTACH_CFG_STRAP
J 0
(-2000 3760);
DISPLAY 0.617021 (-2000 3760);
PAINT ORANGE (-2000 3760);
WIRE 16 -1 (-2150 2150)(-1350 2150);
FORCEPROP 0 LAST SIG_NAME FM_GBE1_LVC3_MOD_ABS
J 0
(-2000 2160);
DISPLAY 0.617021 (-2000 2160);
PAINT ORANGE (-2000 2160);
WIRE 16 -1 (-2150 2050)(-1350 2050);
FORCEPROP 0 LAST SIG_NAME FM_GBE0_LVC3_MOD_ABS
J 0
(-2000 2060);
DISPLAY 0.617021 (-2000 2060);
PAINT ORANGE (-2000 2060);
WIRE 16 -1 (-2150 1950)(-1375 1950);
FORCEPROP 0 LAST SIG_NAME SMB_PCH_MEZZ_LOM3_SCL
J 0
(-2000 1960);
DISPLAY 0.617021 (-2000 1960);
PAINT ORANGE (-2000 1960);
WIRE 16 -1 (-2150 1850)(-1375 1850);
FORCEPROP 0 LAST SIG_NAME SMB_PCH_MEZZ_LOM2_SCL
J 0
(-2000 1860);
DISPLAY 0.617021 (-2000 1860);
PAINT ORANGE (-2000 1860);
WIRE 16 -1 (-2150 1800)(-1400 1800);
FORCEPROP 0 LAST SIG_NAME SMB_PCH_MEZZ_LOM1_SDA
J 0
(-2000 1810);
DISPLAY 0.617021 (-2000 1810);
PAINT ORANGE (-2000 1810);
WIRE 16 -1 (-2150 1700)(-1400 1700);
FORCEPROP 0 LAST SIG_NAME SMB_PCH_MEZZ_LOM0_SDA
J 0
(-2000 1710);
DISPLAY 0.617021 (-2000 1710);
PAINT ORANGE (-2000 1710);
WIRE 16 -1 (-2150 1600)(-1375 1600);
FORCEPROP 2 LAST SIG_NAME LED_GBE_P3_1
J 0
(-2000 1610);
DISPLAY 0.617021 (-2000 1610);
PAINT ORANGE (-2000 1610);
WIRE 16 -1 (-2150 1550)(-1375 1550);
FORCEPROP 2 LAST SIG_NAME LED_GBE_P3_0
J 0
(-2000 1560);
DISPLAY 0.617021 (-2000 1560);
PAINT ORANGE (-2000 1560);
WIRE 16 -1 (-2150 1500)(-1375 1500);
FORCEPROP 2 LAST SIG_NAME LED_GBE_P2_1
J 0
(-2000 1510);
DISPLAY 0.617021 (-2000 1510);
PAINT ORANGE (-2000 1510);
WIRE 16 -1 (-2150 1450)(-1375 1450);
FORCEPROP 2 LAST SIG_NAME LED_GBE_P2_0
J 0
(-2000 1460);
DISPLAY 0.617021 (-2000 1460);
PAINT ORANGE (-2000 1460);
WIRE 16 -1 (-2150 1300)(-1375 1300);
FORCEPROP 2 LAST SIG_NAME LED_GBE_P0_1
J 0
(-2000 1310);
DISPLAY 0.617021 (-2000 1310);
PAINT ORANGE (-2000 1310);
WIRE 16 -1 (-6925 2050)(-6200 2050);
FORCEPROP 0 LAST SIG_NAME FM_ADR_COMPLETE
J 0
(-6925 2060);
DISPLAY 0.617021 (-6925 2060);
PAINT ORANGE (-6925 2060);
WIRE 16 -1 (-6925 2000)(-5350 2000);
FORCEPROP 0 LAST SIG_NAME FM_BOARD_SKU_ID4
J 0
(-6925 2010);
DISPLAY 0.617021 (-6925 2010);
PAINT ORANGE (-6925 2010);
WIRE 16 -1 (-5350 1500)(-6925 1500);
FORCEPROP 2 LAST SIG_NAME FM_CPU1_THERMTRIP_LATCH_LVT3_N
J 0
(-6910 1510);
DISPLAY 0.638298 (-6910 1510);
PAINT ORANGE (-6910 1510);
WIRE 16 -1 (-2150 2200)(-1400 2200);
FORCEPROP 2 LAST SIG_NAME TP_PCH_GPP_J19
J 0
(-2000 2210);
DISPLAY 0.617021 (-2000 2210);
PAINT ORANGE (-2000 2210);
FORCEPROP 2 LASTPROP $XRERR UNIQUE?
J 0
(-1370 2200);
DISPLAY 0.638298 (-1370 2200);
PAINT MONO (-1370 2200);
DISPLAY INVISIBLE (-1370 2200);
WIRE 16 -1 (-2150 2100)(-1400 2100);
FORCEPROP 2 LAST SIG_NAME TP_PCH_GPP_J17
J 0
(-2000 2110);
DISPLAY 0.617021 (-2000 2110);
PAINT ORANGE (-2000 2110);
FORCEPROP 2 LASTPROP $XRERR UNIQUE?
J 0
(-1370 2100);
DISPLAY 0.638298 (-1370 2100);
PAINT MONO (-1370 2100);
DISPLAY INVISIBLE (-1370 2100);
WIRE 3 682 (-1475 3800)(-1950 3800);
WIRE 3 682 (-1950 3850)(-1475 3850);
WIRE 3 682 (-1475 3850)(-1475 3800);
WIRE 3 682 (-1475 3850)(-1400 3850);
WIRE 3 682 (-6075 1750)(-6000 1750);
WIRE 3 682 (-6000 1750)(-5525 1750);
WIRE 3 682 (-6000 1750)(-6000 1200);
WIRE 3 682 (-5525 1200)(-6000 1200);
WIRE 16 -1 (-2150 1650)(-1375 1650);
FORCEPROP 0 LAST SIG_NAME SMB_PCH_MEZZ_LOM0_SCL
J 0
(-2000 1660);
DISPLAY 0.617021 (-2000 1660);
PAINT ORANGE (-2000 1660);
WIRE 16 -1 (-2150 1750)(-1375 1750);
FORCEPROP 0 LAST SIG_NAME SMB_PCH_MEZZ_LOM1_SCL
J 0
(-2000 1760);
DISPLAY 0.617021 (-2000 1760);
PAINT ORANGE (-2000 1760);
WIRE 16 -1 (-2150 2400)(-1400 2400);
FORCEPROP 2 LAST SIG_NAME TP_PCH_GPP_J23
J 0
(-2000 2410);
DISPLAY 0.617021 (-2000 2410);
PAINT ORANGE (-2000 2410);
FORCEPROP 2 LASTPROP $XRERR UNIQUE?
J 0
(-1370 2400);
DISPLAY 0.638298 (-1370 2400);
PAINT MONO (-1370 2400);
DISPLAY INVISIBLE (-1370 2400);
DOT 1 (-1950 3600);
DOT 1 (-6000 1750);
DOT 1 (-1475 3850);
DOT 1 (-6500 3800);
FORCENOTE
TP FAB3-DVT CHANGE CONNECTION 20161117
(-7975 3175) 0;
DISPLAY LEFT (-7975 3175);
DISPLAY 0.638298 (-7975 3175);
PAINT RED (-7975 3175);
FORCENOTE
TP FAB3-DVT RESERVE 0OHM R7W16 20161206
(-1050 2550) 0;
DISPLAY LEFT (-1050 2550);
DISPLAY 0.638298 (-1050 2550);
PAINT RED (-1050 2550);
FORCENOTE
TP FAB3-DVT POP R7W16 20161222
(-1050 2500) 0;
DISPLAY LEFT (-1050 2500);
DISPLAY 0.638298 (-1050 2500);
PAINT RED (-1050 2500);
FORCENOTE
TP FAB3-DVT RESERVE RES R7W11 20161201
(-900 2925) 0;
DISPLAY LEFT (-900 2925);
DISPLAY 0.638298 (-900 2925);
PAINT RED (-900 2925);
FORCENOTE
TP FAB3-DVT POP R7W11 20161222
(-900 2875) 0;
DISPLAY LEFT (-900 2875);
DISPLAY 0.638298 (-900 2875);
PAINT RED (-900 2875);
FORCENOTE
TP FAB1 NC (NO USE IE) 0118
(-1400 3825) 0;
DISPLAY LEFT (-1400 3825);
DISPLAY 0.638298 (-1400 3825);
PAINT RED (-1400 3825);
FORCENOTE
TP FAB1 NC (NO USE IE) 0118
(-1850 3575) 0;
DISPLAY LEFT (-1850 3575);
DISPLAY 0.638298 (-1850 3575);
PAINT RED (-1850 3575);
FORCENOTE
ROOM=SB
(-7800 275) 0;
DISPLAY LEFT (-7800 275);
DISPLAY 1.021277 (-7800 275);
PAINT PURPLE (-7800 275);
FORCENOTE
TP FAB1 NC (NO USE IE) 0118
(-7250 1650) 0;
DISPLAY LEFT (-7250 1650);
DISPLAY 1.021277 (-7250 1650);
PAINT RED (-7250 1650);
FORCENOTE
TP FAB3-DVT ADD 0OHM R7W18 20161207
(-7475 3125) 0;
DISPLAY LEFT (-7475 3125);
DISPLAY 0.638298 (-7475 3125);
PAINT RED (-7475 3125);
FORCENOTE
TP FAB3-DVT POP R7W14 20161222
(-7500 2800) 0;
DISPLAY LEFT (-7500 2800);
DISPLAY 0.638298 (-7500 2800);
PAINT RED (-7500 2800);
FORCENOTE
TP FAB3-DVT RESERVE RES R7W14 20161206
(-7500 2850) 0;
DISPLAY LEFT (-7500 2850);
DISPLAY 0.638298 (-7500 2850);
PAINT RED (-7500 2850);
FORCENOTE
TP FAB3-DVT RESERVE RES R7W8, R7W10, R7W12 20161201
(-7750 3575) 0;
DISPLAY LEFT (-7750 3575);
DISPLAY 0.638298 (-7750 3575);
PAINT RED (-7750 3575);
FORCENOTE
TP FAB4 POP R7W8 20170117
(-7750 3425) 0;
DISPLAY LEFT (-7750 3425);
DISPLAY 0.638298 (-7750 3425);
PAINT RED (-7750 3425);
FORCENOTE
TP FAB4 POP R7W10 20170116
(-7750 3475) 0;
DISPLAY LEFT (-7750 3475);
DISPLAY 0.638298 (-7750 3475);
PAINT RED (-7750 3475);
FORCENOTE
TP FAB3-DVT POP R7W12 20161222
(-7750 3525) 0;
DISPLAY LEFT (-7750 3525);
DISPLAY 0.638298 (-7750 3525);
PAINT RED (-7750 3525);
FORCENOTE
TP FAB4 NOPOP R7W20 20170117
(-6250 4575) 0;
DISPLAY LEFT (-6250 4575);
DISPLAY 0.638298 (-6250 4575);
PAINT RED (-6250 4575);
FORCENOTE
TP FAB4 ADD R7W20 20170116
(-6250 4625) 0;
DISPLAY LEFT (-6250 4625);
DISPLAY 0.638298 (-6250 4625);
PAINT RED (-6250 4625);
QUIT
